G04 ================== begin FILE IDENTIFICATION RECORD ==================*
G04 Layout Name:  13948-1b.brd*
G04 Film Name:    L2GND*
G04 File Format:  Gerber RS274X*
G04 File Origin:  Cadence Allegro 16.5-S045*
G04 Origin Date:  Thu Nov 13 15:46:08 2014*
G04 *
G04 Layer:  VIA CLASS/L2GND*
G04 Layer:  PIN/L2GND*
G04 Layer:  ETCH/L2GND*
G04 Layer:  DRAWING FORMAT/LAYER_PCB_STORY*
G04 Layer:  DRAWING FORMAT/LAYER_L2GND*
G04 *
G04 Offset:    (0.00 0.00)*
G04 Mirror:    No*
G04 Mode:      Negative*
G04 Rotation:  0*
G04 FullContactRelief:  No*
G04 UndefLineWidth:     6.00*
G04 ================== end FILE IDENTIFICATION RECORD ====================*
%FSLAX35Y35*MOIN*%
%IR0*IPPOS*OFA0.00000B0.00000*MIA0B0*SFA1.00000B1.00000*%
%ADD17C,.03*%
%ADD13C,.032*%
%ADD47C,.06*%
%ADD43C,.07*%
%ADD42C,.062*%
%ADD19C,.036*%
%ADD18C,.063*%
%ADD12C,.09*%
%ADD36C,.064*%
%ADD22C,.073*%
%ADD39C,.066*%
%ADD31C,.057*%
%ADD41C,.076*%
%ADD28C,.059*%
%ADD24C,.068*%
%ADD33C,.078*%
%ADD15C,.089*%
%AMMACRO44*
4,1,14,.02707,.01293,
.028904,.008033,
.02986,.002892,
.029908,-.002337,
.029048,-.007495,
.027305,-.012426,
.02707,-.01293,
.03079,-.01665,
.033213,-.01105,
.034628,-.005115,
.03499,.000976,
.034289,.007037,
.032546,.012884,
.03079,.01665,
.02707,.01293,
270.*
4,1,14,.01293,-.02707,
.008033,-.028904,
.002892,-.02986,
-.002337,-.029908,
-.007495,-.029048,
-.012426,-.027305,
-.01293,-.02707,
-.01665,-.03079,
-.01105,-.033213,
-.005115,-.034628,
.000976,-.03499,
.007037,-.034289,
.012884,-.032546,
.01665,-.03079,
.01293,-.02707,
270.*
4,1,14,-.02707,-.01293,
-.028904,-.008033,
-.02986,-.002892,
-.029908,.002337,
-.029048,.007495,
-.027305,.012426,
-.02707,.01293,
-.03079,.01665,
-.033213,.01105,
-.034628,.005115,
-.03499,-.000976,
-.034289,-.007037,
-.032546,-.012884,
-.03079,-.01665,
-.02707,-.01293,
270.*
4,1,14,-.01293,.02707,
-.008033,.028904,
-.002892,.02986,
.002337,.029908,
.007495,.029048,
.012426,.027305,
.01293,.02707,
.01665,.03079,
.01105,.033213,
.005115,.034628,
-.000976,.03499,
-.007037,.034289,
-.012884,.032546,
-.01665,.03079,
-.01293,.02707,
270.*
%
%ADD44MACRO44*%
%AMMACRO29*
4,1,15,.00398,.00044,
.003999,.000208,
.004004,-.000025,
.003996,-.000258,
.00398,-.00044,
.00483,-.00129,
.004897,-.001007,
.004947,-.000721,
.004981,-.000432,
.004997,-.000141,
.004997,.000149,
.00498,.00044,
.004946,.000729,
.004895,.001015,
.00483,.00129,
.00398,.00044,
90.*
4,1,15,.00044,-.00398,
.000208,-.003999,
-.000025,-.004004,
-.000258,-.003996,
-.00044,-.00398,
-.00129,-.00483,
-.001007,-.004897,
-.000721,-.004947,
-.000432,-.004981,
-.000141,-.004997,
.000149,-.004997,
.00044,-.00498,
.000729,-.004946,
.001015,-.004895,
.00129,-.00483,
.00044,-.00398,
90.*
4,1,15,-.00398,-.00044,
-.003999,-.000208,
-.004004,.000025,
-.003996,.000258,
-.00398,.00044,
-.00483,.00129,
-.004897,.001007,
-.004947,.000721,
-.004981,.000432,
-.004997,.000141,
-.004997,-.000149,
-.00498,-.00044,
-.004946,-.000729,
-.004895,-.001015,
-.00483,-.00129,
-.00398,-.00044,
90.*
4,1,15,-.00044,.00398,
-.000208,.003999,
.000025,.004004,
.000258,.003996,
.00044,.00398,
.00129,.00483,
.001007,.004897,
.000721,.004947,
.000432,.004981,
.000141,.004997,
-.000149,.004997,
-.00044,.00498,
-.000729,.004946,
-.001015,.004895,
-.00129,.00483,
-.00044,.00398,
90.*
%
%ADD29MACRO29*%
%AMMACRO10*
4,1,15,.00398,.00044,
.003999,.000208,
.004004,-.000025,
.003996,-.000258,
.00398,-.00044,
.00483,-.00129,
.004897,-.001007,
.004947,-.000721,
.004981,-.000432,
.004997,-.000141,
.004997,.000149,
.00498,.00044,
.004946,.000729,
.004895,.001015,
.00483,.00129,
.00398,.00044,
0.0*
4,1,15,.00044,-.00398,
.000208,-.003999,
-.000025,-.004004,
-.000258,-.003996,
-.00044,-.00398,
-.00129,-.00483,
-.001007,-.004897,
-.000721,-.004947,
-.000432,-.004981,
-.000141,-.004997,
.000149,-.004997,
.00044,-.00498,
.000729,-.004946,
.001015,-.004895,
.00129,-.00483,
.00044,-.00398,
0.0*
4,1,15,-.00398,-.00044,
-.003999,-.000208,
-.004004,.000025,
-.003996,.000258,
-.00398,.00044,
-.00483,.00129,
-.004897,.001007,
-.004947,.000721,
-.004981,.000432,
-.004997,.000141,
-.004997,-.000149,
-.00498,-.00044,
-.004946,-.000729,
-.004895,-.001015,
-.00483,-.00129,
-.00398,-.00044,
0.0*
4,1,15,-.00044,.00398,
-.000208,.003999,
.000025,.004004,
.000258,.003996,
.00044,.00398,
.00129,.00483,
.001007,.004897,
.000721,.004947,
.000432,.004981,
.000141,.004997,
-.000149,.004997,
-.00044,.00498,
-.000729,.004946,
-.001015,.004895,
-.00129,.00483,
-.00044,.00398,
0.0*
%
%ADD10MACRO10*%
%AMMACRO45*
4,1,13,.02442,.01028,
.025834,.005883,
.026463,.001308,
.026288,-.003307,
.025315,-.007822,
.02442,-.01028,
.02819,-.01405,
.030201,-.008941,
.031295,-.003561,
.031438,.001927,
.030626,.007357,
.028883,.012564,
.02819,.01405,
.02442,.01028,
180.*
4,1,13,.01028,-.02442,
.005883,-.025834,
.001308,-.026463,
-.003307,-.026288,
-.007822,-.025315,
-.01028,-.02442,
-.01405,-.02819,
-.008941,-.030201,
-.003561,-.031295,
.001927,-.031438,
.007357,-.030626,
.012564,-.028883,
.01405,-.02819,
.01028,-.02442,
180.*
4,1,13,-.02442,-.01028,
-.025834,-.005883,
-.026463,-.001308,
-.026288,.003307,
-.025315,.007822,
-.02442,.01028,
-.02819,.01405,
-.030201,.008941,
-.031295,.003561,
-.031438,-.001927,
-.030626,-.007357,
-.028883,-.012564,
-.02819,-.01405,
-.02442,-.01028,
180.*
4,1,13,-.01028,.02442,
-.005883,.025834,
-.001308,.026463,
.003307,.026288,
.007822,.025315,
.01028,.02442,
.01405,.02819,
.008941,.030201,
.003561,.031295,
-.001927,.031438,
-.007357,.030626,
-.012564,.028883,
-.01405,.02819,
-.01028,.02442,
180.*
%
%ADD45MACRO45*%
%AMMACRO32*
4,1,19,.02211,.00797,
.022536,.006671,
.022886,.005349,
.023158,.00401,
.023352,.002656,
.023467,.001294,
.023503,-.000073,
.023459,-.001439,
.023335,-.002801,
.023133,-.004153,
.022852,-.005491,
.022494,-.00681,
.02211,-.00797,
.02594,-.0118,
.027595,-.007116,
.028411,-.002216,
.028365,.002751,
.027456,.007635,
.02594,.0118,
.02211,.00797,
180.*
4,1,19,.00797,-.02211,
.006671,-.022536,
.005349,-.022886,
.00401,-.023158,
.002656,-.023352,
.001294,-.023467,
-.000073,-.023503,
-.001439,-.023459,
-.002801,-.023335,
-.004153,-.023133,
-.005491,-.022852,
-.00681,-.022494,
-.00797,-.02211,
-.0118,-.02594,
-.007116,-.027595,
-.002216,-.028411,
.002751,-.028365,
.007635,-.027456,
.0118,-.02594,
.00797,-.02211,
180.*
4,1,19,-.02211,-.00797,
-.022536,-.006671,
-.022886,-.005349,
-.023158,-.00401,
-.023352,-.002656,
-.023467,-.001294,
-.023503,.000073,
-.023459,.001439,
-.023335,.002801,
-.023133,.004153,
-.022852,.005491,
-.022494,.00681,
-.02211,.00797,
-.02594,.0118,
-.027595,.007116,
-.028411,.002216,
-.028365,-.002751,
-.027456,-.007635,
-.02594,-.0118,
-.02211,-.00797,
180.*
4,1,19,-.00797,.02211,
-.006671,.022536,
-.005349,.022886,
-.00401,.023158,
-.002656,.023352,
-.001294,.023467,
.000073,.023503,
.001439,.023459,
.002801,.023335,
.004153,.023133,
.005491,.022852,
.00681,.022494,
.00797,.02211,
.0118,.02594,
.007116,.027595,
.002216,.028411,
-.002751,.028365,
-.007635,.027456,
-.0118,.02594,
-.00797,.02211,
180.*
%
%ADD32MACRO32*%
%AMMACRO46*
4,1,13,.02632,.01218,
.028035,.007425,
.028899,.002443,
.028884,-.002612,
.027991,-.007588,
.02632,-.01218,
.03005,-.01591,
.032356,-.01045,
.033679,-.004673,
.033979,.001247,
.033246,.007128,
.031504,.012793,
.03005,.01591,
.02632,.01218,
180.*
4,1,13,.01218,-.02632,
.007425,-.028035,
.002443,-.028899,
-.002612,-.028884,
-.007588,-.027991,
-.01218,-.02632,
-.01591,-.03005,
-.01045,-.032356,
-.004673,-.033679,
.001247,-.033979,
.007128,-.033246,
.012793,-.031504,
.01591,-.03005,
.01218,-.02632,
180.*
4,1,13,-.02632,-.01218,
-.028035,-.007425,
-.028899,-.002443,
-.028884,.002612,
-.027991,.007588,
-.02632,.01218,
-.03005,.01591,
-.032356,.01045,
-.033679,.004673,
-.033979,-.001247,
-.033246,-.007128,
-.031504,-.012793,
-.03005,-.01591,
-.02632,-.01218,
180.*
4,1,13,-.01218,.02632,
-.007425,.028035,
-.002443,.028899,
.002612,.028884,
.007588,.027991,
.01218,.02632,
.01591,.03005,
.01045,.032356,
.004673,.033679,
-.001247,.033979,
-.007128,.033246,
-.012793,.031504,
-.01591,.03005,
-.01218,.02632,
180.*
%
%ADD46MACRO46*%
%AMMACRO23*
4,1,13,.02632,.01218,
.028035,.007425,
.028899,.002443,
.028884,-.002612,
.027991,-.007588,
.02632,-.01218,
.03005,-.01591,
.032356,-.01045,
.033679,-.004673,
.033979,.001247,
.033246,.007128,
.031504,.012793,
.03005,.01591,
.02632,.01218,
270.*
4,1,13,.01218,-.02632,
.007425,-.028035,
.002443,-.028899,
-.002612,-.028884,
-.007588,-.027991,
-.01218,-.02632,
-.01591,-.03005,
-.01045,-.032356,
-.004673,-.033679,
.001247,-.033979,
.007128,-.033246,
.012793,-.031504,
.01591,-.03005,
.01218,-.02632,
270.*
4,1,13,-.02632,-.01218,
-.028035,-.007425,
-.028899,-.002443,
-.028884,.002612,
-.027991,.007588,
-.02632,.01218,
-.03005,.01591,
-.032356,.01045,
-.033679,.004673,
-.033979,-.001247,
-.033246,-.007128,
-.031504,-.012793,
-.03005,-.01591,
-.02632,-.01218,
270.*
4,1,13,-.01218,.02632,
-.007425,.028035,
-.002443,.028899,
.002612,.028884,
.007588,.027991,
.01218,.02632,
.01591,.03005,
.01045,.032356,
.004673,.033679,
-.001247,.033979,
-.007128,.033246,
-.012793,.031504,
-.01591,.03005,
-.01218,.02632,
270.*
%
%ADD23MACRO23*%
%ADD37O,.217X.154*%
%ADD30C,.121*%
%ADD14C,.114*%
%ADD26C,.154*%
%ADD38C,.119*%
%ADD35C,.156*%
%ADD27C,.166*%
%AMMACRO20*
4,1,15,.00398,.00044,
.003999,.000208,
.004004,-.000025,
.003996,-.000258,
.00398,-.00044,
.00483,-.00129,
.004897,-.001007,
.004947,-.000721,
.004981,-.000432,
.004997,-.000141,
.004997,.000149,
.00498,.00044,
.004946,.000729,
.004895,.001015,
.00483,.00129,
.00398,.00044,
180.*
4,1,15,.00044,-.00398,
.000208,-.003999,
-.000025,-.004004,
-.000258,-.003996,
-.00044,-.00398,
-.00129,-.00483,
-.001007,-.004897,
-.000721,-.004947,
-.000432,-.004981,
-.000141,-.004997,
.000149,-.004997,
.00044,-.00498,
.000729,-.004946,
.001015,-.004895,
.00129,-.00483,
.00044,-.00398,
180.*
4,1,15,-.00398,-.00044,
-.003999,-.000208,
-.004004,.000025,
-.003996,.000258,
-.00398,.00044,
-.00483,.00129,
-.004897,.001007,
-.004947,.000721,
-.004981,.000432,
-.004997,.000141,
-.004997,-.000149,
-.00498,-.00044,
-.004946,-.000729,
-.004895,-.001015,
-.00483,-.00129,
-.00398,-.00044,
180.*
4,1,15,-.00044,.00398,
-.000208,.003999,
.000025,.004004,
.000258,.003996,
.00044,.00398,
.00129,.00483,
.001007,.004897,
.000721,.004947,
.000432,.004981,
.000141,.004997,
-.000149,.004997,
-.00044,.00498,
-.000729,.004946,
-.001015,.004895,
-.00129,.00483,
-.00044,.00398,
180.*
%
%ADD20MACRO20*%
%AMMACRO16*
4,1,15,.00398,.00044,
.003999,.000208,
.004004,-.000025,
.003996,-.000258,
.00398,-.00044,
.00483,-.00129,
.004897,-.001007,
.004947,-.000721,
.004981,-.000432,
.004997,-.000141,
.004997,.000149,
.00498,.00044,
.004946,.000729,
.004895,.001015,
.00483,.00129,
.00398,.00044,
270.*
4,1,15,.00044,-.00398,
.000208,-.003999,
-.000025,-.004004,
-.000258,-.003996,
-.00044,-.00398,
-.00129,-.00483,
-.001007,-.004897,
-.000721,-.004947,
-.000432,-.004981,
-.000141,-.004997,
.000149,-.004997,
.00044,-.00498,
.000729,-.004946,
.001015,-.004895,
.00129,-.00483,
.00044,-.00398,
270.*
4,1,15,-.00398,-.00044,
-.003999,-.000208,
-.004004,.000025,
-.003996,.000258,
-.00398,.00044,
-.00483,.00129,
-.004897,.001007,
-.004947,.000721,
-.004981,.000432,
-.004997,.000141,
-.004997,-.000149,
-.00498,-.00044,
-.004946,-.000729,
-.004895,-.001015,
-.00483,-.00129,
-.00398,-.00044,
270.*
4,1,15,-.00044,.00398,
-.000208,.003999,
.000025,.004004,
.000258,.003996,
.00044,.00398,
.00129,.00483,
.001007,.004897,
.000721,.004947,
.000432,.004981,
.000141,.004997,
-.000149,.004997,
-.00044,.00498,
-.000729,.004946,
-.001015,.004895,
-.00129,.00483,
-.00044,.00398,
270.*
%
%ADD16MACRO16*%
%AMMACRO21*
4,1,13,.02327,.00913,
.024502,.004951,
.024989,.000621,
.024717,-.003728,
.023695,-.007964,
.02327,-.00913,
.02707,-.01293,
.028904,-.008033,
.02986,-.002892,
.029908,.002337,
.029048,.007495,
.027305,.012426,
.02707,.01293,
.02327,.00913,
0.0*
4,1,13,.00913,-.02327,
.004951,-.024502,
.000621,-.024989,
-.003728,-.024717,
-.007964,-.023695,
-.00913,-.02327,
-.01293,-.02707,
-.008033,-.028904,
-.002892,-.02986,
.002337,-.029908,
.007495,-.029048,
.012426,-.027305,
.01293,-.02707,
.00913,-.02327,
0.0*
4,1,13,-.02327,-.00913,
-.024502,-.004951,
-.024989,-.000621,
-.024717,.003728,
-.023695,.007964,
-.02327,.00913,
-.02707,.01293,
-.028904,.008033,
-.02986,.002892,
-.029908,-.002337,
-.029048,-.007495,
-.027305,-.012426,
-.02707,-.01293,
-.02327,-.00913,
0.0*
4,1,13,-.00913,.02327,
-.004951,.024502,
-.000621,.024989,
.003728,.024717,
.007964,.023695,
.00913,.02327,
.01293,.02707,
.008033,.028904,
.002892,.02986,
-.002337,.029908,
-.007495,.029048,
-.012426,.027305,
-.01293,.02707,
-.00913,.02327,
0.0*
%
%ADD21MACRO21*%
%AMMACRO34*
4,1,13,.03683,.01561,
.038981,.008977,
.039948,.002072,
.039701,-.004896,
.038247,-.011716,
.03683,-.01561,
.04061,-.01939,
.04336,-.012044,
.044793,-.004331,
.044864,.003513,
.043573,.01125,
.040957,.018645,
.04061,.01939,
.03683,.01561,
0.0*
4,1,13,.01561,-.03683,
.008977,-.038981,
.002072,-.039948,
-.004896,-.039701,
-.011716,-.038247,
-.01561,-.03683,
-.01939,-.04061,
-.012044,-.04336,
-.004331,-.044793,
.003513,-.044864,
.01125,-.043573,
.018645,-.040957,
.01939,-.04061,
.01561,-.03683,
0.0*
4,1,13,-.03683,-.01561,
-.038981,-.008977,
-.039948,-.002072,
-.039701,.004896,
-.038247,.011716,
-.03683,.01561,
-.04061,.01939,
-.04336,.012044,
-.044793,.004331,
-.044864,-.003513,
-.043573,-.01125,
-.040957,-.018645,
-.04061,-.01939,
-.03683,-.01561,
0.0*
4,1,13,-.01561,.03683,
-.008977,.038981,
-.002072,.039948,
.004896,.039701,
.011716,.038247,
.01561,.03683,
.01939,.04061,
.012044,.04336,
.004331,.044793,
-.003513,.044864,
-.01125,.043573,
-.018645,.040957,
-.01939,.04061,
-.01561,.03683,
0.0*
%
%ADD34MACRO34*%
%AMMACRO25*
4,1,14,.02819,.01405,
.030201,.008941,
.031295,.003561,
.031438,-.001927,
.030626,-.007357,
.028883,-.012564,
.02819,-.01405,
.03189,-.01775,
.034488,-.011943,
.036038,-.005773,
.036493,.000573,
.035839,.006901,
.034096,.01302,
.03189,.01775,
.02819,.01405,
0.0*
4,1,14,.01405,-.02819,
.008941,-.030201,
.003561,-.031295,
-.001927,-.031438,
-.007357,-.030626,
-.012564,-.028883,
-.01405,-.02819,
-.01775,-.03189,
-.011943,-.034488,
-.005773,-.036038,
.000573,-.036493,
.006901,-.035839,
.01302,-.034096,
.01775,-.03189,
.01405,-.02819,
0.0*
4,1,14,-.02819,-.01405,
-.030201,-.008941,
-.031295,-.003561,
-.031438,.001927,
-.030626,.007357,
-.028883,.012564,
-.02819,.01405,
-.03189,.01775,
-.034488,.011943,
-.036038,.005773,
-.036493,-.000573,
-.035839,-.006901,
-.034096,-.01302,
-.03189,-.01775,
-.02819,-.01405,
0.0*
4,1,14,-.01405,.02819,
-.008941,.030201,
-.003561,.031295,
.001927,.031438,
.007357,.030626,
.012564,.028883,
.01405,.02819,
.01775,.03189,
.011943,.034488,
.005773,.036038,
-.000573,.036493,
-.006901,.035839,
-.01302,.034096,
-.01775,.03189,
-.01405,.02819,
0.0*
%
%ADD25MACRO25*%
%AMMACRO11*
4,1,14,.0575,.02922,
.0617,.018791,
.064026,.007792,
.064406,-.003445,
.06283,-.014576,
.059344,-.025265,
.0575,-.02922,
.06121,-.03292,
.065997,-.021791,
.068778,-.01,
.069469,.002095,
.06805,.014127,
.064563,.025729,
.06121,.03292,
.0575,.02922,
90.*
4,1,14,.02922,-.0575,
.018791,-.0617,
.007792,-.064026,
-.003445,-.064406,
-.014576,-.06283,
-.025265,-.059344,
-.02922,-.0575,
-.03292,-.06121,
-.021791,-.065997,
-.01,-.068778,
.002095,-.069469,
.014127,-.06805,
.025729,-.064563,
.03292,-.06121,
.02922,-.0575,
90.*
4,1,14,-.0575,-.02922,
-.0617,-.018791,
-.064026,-.007792,
-.064406,.003445,
-.06283,.014576,
-.059344,.025265,
-.0575,.02922,
-.06121,.03292,
-.065997,.021791,
-.068778,.01,
-.069469,-.002095,
-.06805,-.014127,
-.064563,-.025729,
-.06121,-.03292,
-.0575,-.02922,
90.*
4,1,14,-.02922,.0575,
-.018791,.0617,
-.007792,.064026,
.003445,.064406,
.014576,.06283,
.025265,.059344,
.02922,.0575,
.03292,.06121,
.021791,.065997,
.01,.068778,
-.002095,.069469,
-.014127,.06805,
-.025729,.064563,
-.03292,.06121,
-.02922,.0575,
90.*
%
%ADD11MACRO11*%
%AMMACRO40*
4,1,13,.02556,.01142,
.027155,.006808,
.027924,.001989,
.027846,-.00289,
.026921,-.007681,
.02556,-.01142,
.02931,-.01517,
.031499,-.00985,
.032731,-.004231,
.032968,.001517,
.032204,.007219,
.030461,.012702,
.02931,.01517,
.02556,.01142,
0.0*
4,1,13,.01142,-.02556,
.006808,-.027155,
.001989,-.027924,
-.00289,-.027846,
-.007681,-.026921,
-.01142,-.02556,
-.01517,-.02931,
-.00985,-.031499,
-.004231,-.032731,
.001517,-.032968,
.007219,-.032204,
.012702,-.030461,
.01517,-.02931,
.01142,-.02556,
0.0*
4,1,13,-.02556,-.01142,
-.027155,-.006808,
-.027924,-.001989,
-.027846,.00289,
-.026921,.007681,
-.02556,.01142,
-.02931,.01517,
-.031499,.00985,
-.032731,.004231,
-.032968,-.001517,
-.032204,-.007219,
-.030461,-.012702,
-.02931,-.01517,
-.02556,-.01142,
0.0*
4,1,13,-.01142,.02556,
-.006808,.027155,
-.001989,.027924,
.00289,.027846,
.007681,.026921,
.01142,.02556,
.01517,.02931,
.00985,.031499,
.004231,.032731,
-.001517,.032968,
-.007219,.032204,
-.012702,.030461,
-.01517,.02931,
-.01142,.02556,
0.0*
%
%ADD40MACRO40*%
%ADD48C,.02*%
%ADD49C,.006*%
%ADD64C,.06204*%
%ADD62C,.07204*%
%ADD60C,.06404*%
%ADD65C,.05604*%
%ADD63C,.05804*%
%ADD55C,.08504*%
%ADD54C,.08604*%
%ADD67C,.06904*%
%ADD50O,.21302X.15002*%
%ADD51O,.21304X.15004*%
%ADD56C,.15004*%
%ADD59C,.15204*%
%ADD58C,.11704*%
%ADD57C,.16204*%
%ADD52O,.02222X.07922*%
%ADD69R,.03124X.04824*%
%ADD66R,.05324X.05324*%
%ADD53O,.02224X.07924*%
%ADD61R,.08504X.05504*%
%ADD68R,.04924X.05724*%
G75*
%LPD*%
G75*
G36*
G01X-6000Y-6000D02*
X1406000D01*
Y1029622D01*
X-6000D01*
Y-6000D01*
G37*
%LPC*%
G75*
G36*
G01X297047Y3004D02*
G02X296114Y3937I0J933D01*
G01Y62992D01*
G03X289173Y69933I-6941J0D01*
G01X247835D01*
G02X246902Y70866I0J933D01*
G01Y224449D01*
G03X239961Y231390I-6941J0D01*
G01X116142D01*
G02X111272Y236260I0J4870D01*
G01Y299252D01*
G03X100394Y310130I-10878J0D01*
G01X11811D01*
G02X3004Y318937I0J8807D01*
G01Y968504D01*
G02X19685Y985185I16681J0D01*
G01X103740D01*
G03X110681Y992126I0J6941D01*
G01Y1008110D01*
X133020D01*
Y994291D01*
G03X146508I6744J0D01*
G01Y1008110D01*
X184594D01*
Y992126D01*
G03X191535Y985185I6941J0D01*
G01X261220D01*
G03X268161Y992126I0J6941D01*
G01Y1001600D01*
X542468D01*
Y994291D01*
G03X555957I6744J0D01*
G01Y1001600D01*
X594043D01*
Y992126D01*
G03X600984Y985185I6941J0D01*
G01X713189D01*
G03X720130Y992126I0J6941D01*
G01Y1008110D01*
X742468D01*
Y994291D01*
G03X755957I6745J0D01*
G01Y1008110D01*
X794043D01*
Y992126D01*
G03X800984Y985185I6941J0D01*
G01X902165D01*
G02X918846Y968504I0J-16681D01*
G01Y775591D01*
G03X925787Y768650I6941J0D01*
G01X984843D01*
G03X991784Y775591I0J6941D01*
G01Y968504D01*
G02X1008465Y985185I16681J0D01*
G01X1380315D01*
G02X1396996Y968504I0J-16681D01*
G01Y3937D01*
G02X1396063Y3004I-933J0D01*
G01X1210571D01*
G02X1209638Y3937I0J933D01*
G01Y171260D01*
G03X1202697Y178201I-6941J0D01*
G02X1201764Y179134I0J933D01*
G01Y210630D01*
G03X1194823Y217571I-6941J0D01*
G01X1116083D01*
G03X1109142Y210630I0J-6941D01*
G01Y3937D01*
G02X1108209Y3004I-933J0D01*
G01X297047D01*
G37*
%LPD*%
G75*
G36*
G01X480978Y873812D02*
G02X481790Y873000I0J-812D01*
G01Y871600D01*
G02X480978Y870788I-812J0D01*
G01X479578D01*
G02X478766Y871600I0J812D01*
G01Y873000D01*
G02X479578Y873812I812J0D01*
G01X480978D01*
G37*
G36*
G01X474478D02*
G02X475290Y873000I0J-812D01*
G01Y871600D01*
G02X474478Y870788I-812J0D01*
G01X473078D01*
G02X472266Y871600I0J812D01*
G01Y873000D01*
G02X473078Y873812I812J0D01*
G01X474478D01*
G37*
G36*
G01X476478Y813712D02*
G02X477290Y812900I0J-812D01*
G01Y811500D01*
G02X476478Y810688I-812J0D01*
G01X475078D01*
G02X474266Y811500I0J812D01*
G01Y812900D01*
G02X475078Y813712I812J0D01*
G01X476478D01*
G37*
G36*
G01X469978D02*
G02X470790Y812900I0J-812D01*
G01Y811500D01*
G02X469978Y810688I-812J0D01*
G01X468578D01*
G02X467766Y811500I0J812D01*
G01Y812900D01*
G02X468578Y813712I812J0D01*
G01X469978D01*
G37*
G36*
G01X451478Y873812D02*
G02X452290Y873000I0J-812D01*
G01Y871600D01*
G02X451478Y870788I-812J0D01*
G01X450078D01*
G02X449266Y871600I0J812D01*
G01Y873000D01*
G02X450078Y873812I812J0D01*
G01X451478D01*
G37*
G36*
G01X444978D02*
G02X445790Y873000I0J-812D01*
G01Y871600D01*
G02X444978Y870788I-812J0D01*
G01X443578D01*
G02X442766Y871600I0J812D01*
G01Y873000D01*
G02X443578Y873812I812J0D01*
G01X444978D01*
G37*
G36*
G01X445478Y813712D02*
G02X446290Y812900I0J-812D01*
G01Y811500D01*
G02X445478Y810688I-812J0D01*
G01X444078D01*
G02X443266Y811500I0J812D01*
G01Y812900D01*
G02X444078Y813712I812J0D01*
G01X445478D01*
G37*
G36*
G01X438978D02*
G02X439790Y812900I0J-812D01*
G01Y811500D01*
G02X438978Y810688I-812J0D01*
G01X437578D01*
G02X436766Y811500I0J812D01*
G01Y812900D01*
G02X437578Y813712I812J0D01*
G01X438978D01*
G37*
G36*
G01X1123260Y727579D02*
X1120812Y727928D01*
X1120781Y727923D01*
G02X1121211Y730936I-281J1577D01*
G01X1121240Y730921D01*
X1123688Y730572D01*
X1123720Y730577D01*
G02X1123289Y727564I280J-1577D01*
G01X1123260Y727579D01*
G37*
G36*
G01X1180141Y690540D02*
X1180172Y690530D01*
X1182283Y690559D01*
X1182314Y690570D01*
G02X1182354Y687726I503J-1415D01*
G01X1182323Y687736D01*
X1180212Y687707D01*
X1180181Y687696D01*
G02X1180141Y690540I-503J1415D01*
G37*
G36*
G01X1192392Y682405D02*
X1192363Y682415D01*
X1190322Y682510D01*
X1190293Y682502D01*
G02X1190435Y685559I-403J1551D01*
G01X1190464Y685549D01*
X1192505Y685454D01*
X1192534Y685462D01*
G02X1192392Y682405I403J-1551D01*
G37*
G36*
G01X1379639Y609381D02*
G03Y608848I298J-266D01*
G02X1376353I-1643J-1466D01*
G03Y609381I-298J267D01*
G02X1379639I1643J1466D01*
G37*
G36*
G01X1382336Y600343D02*
Y600007D01*
X1382402Y599948D01*
G02X1379448I-1477J-1633D01*
G01X1379514Y600007D01*
Y600343D01*
X1379448Y600402D01*
G02X1382402I1477J1633D01*
G01X1382336Y600343D01*
G37*
G36*
G01X1383443Y579784D02*
X1383107D01*
X1383048Y579718D01*
G02Y582672I-1633J1477D01*
G01X1383107Y582606D01*
X1383443D01*
X1383502Y582672D01*
G02Y579718I1633J-1477D01*
G01X1383443Y579784D01*
G37*
G36*
G01X481066Y448400D02*
G02X480455Y447788I-611J-1D01*
G01X479655D01*
G02X479044Y448400I1J612D01*
G01Y449400D01*
G02X479163Y449763I611J1D01*
G03Y450237I-322J237D01*
G02X479044Y450600I492J362D01*
G01Y451600D01*
G02X479655Y452212I611J1D01*
G01X480455D01*
G02X481066Y451600I-1J-612D01*
G01Y450600D01*
G02X480947Y450237I-611J-1D01*
G03Y449763I322J-237D01*
G02X481066Y449400I-492J-362D01*
G01Y448400D01*
G37*
G36*
G01X478566D02*
G02X477955Y447788I-611J-1D01*
G01X477155D01*
G02X476544Y448400I1J612D01*
G01Y449400D01*
G02X476663Y449763I611J1D01*
G03Y450237I-322J237D01*
G02X476544Y450600I492J362D01*
G01Y451600D01*
G02X477155Y452212I611J1D01*
G01X477955D01*
G02X478566Y451600I-1J-612D01*
G01Y450600D01*
G02X478447Y450237I-611J-1D01*
G03Y449763I322J-237D01*
G02X478566Y449400I-492J-362D01*
G01Y448400D01*
G37*
G36*
G01X474066D02*
G02X473455Y447788I-611J-1D01*
G01X472655D01*
G02X472044Y448400I1J612D01*
G01Y449400D01*
G02X472163Y449763I611J1D01*
G03Y450237I-322J237D01*
G02X472044Y450600I492J362D01*
G01Y451600D01*
G02X472655Y452212I611J1D01*
G01X473455D01*
G02X474066Y451600I-1J-612D01*
G01Y450600D01*
G02X473947Y450237I-611J-1D01*
G03Y449763I322J-237D01*
G02X474066Y449400I-492J-362D01*
G01Y448400D01*
G37*
G36*
G01X471566D02*
G02X470955Y447788I-611J-1D01*
G01X470155D01*
G02X469544Y448400I1J612D01*
G01Y449400D01*
G02X469663Y449763I611J1D01*
G03Y450237I-322J237D01*
G02X469544Y450600I492J362D01*
G01Y451600D01*
G02X470155Y452212I611J1D01*
G01X470955D01*
G02X471566Y451600I-1J-612D01*
G01Y450600D01*
G02X471447Y450237I-611J-1D01*
G03Y449763I322J-237D01*
G02X471566Y449400I-492J-362D01*
G01Y448400D01*
G37*
G36*
G01X467066D02*
G02X466455Y447788I-611J-1D01*
G01X465655D01*
G02X465044Y448400I1J612D01*
G01Y449400D01*
G02X465163Y449763I611J1D01*
G03Y450237I-322J237D01*
G02X465044Y450600I492J362D01*
G01Y451600D01*
G02X465655Y452212I611J1D01*
G01X466455D01*
G02X467066Y451600I-1J-612D01*
G01Y450600D01*
G02X466947Y450237I-611J-1D01*
G03Y449763I322J-237D01*
G02X467066Y449400I-492J-362D01*
G01Y448400D01*
G37*
G36*
G01X464566D02*
G02X463955Y447788I-611J-1D01*
G01X463155D01*
G02X462544Y448400I1J612D01*
G01Y449400D01*
G02X462663Y449763I611J1D01*
G03Y450237I-322J237D01*
G02X462544Y450600I492J362D01*
G01Y451600D01*
G02X463155Y452212I611J1D01*
G01X463955D01*
G02X464566Y451600I-1J-612D01*
G01Y450600D01*
G02X464447Y450237I-611J-1D01*
G03Y449763I322J-237D01*
G02X464566Y449400I-492J-362D01*
G01Y448400D01*
G37*
G36*
G01X460066D02*
G02X459455Y447788I-611J-1D01*
G01X458655D01*
G02X458044Y448400I1J612D01*
G01Y449400D01*
G02X458163Y449763I611J1D01*
G03Y450237I-322J237D01*
G02X458044Y450600I492J362D01*
G01Y451600D01*
G02X458655Y452212I611J1D01*
G01X459455D01*
G02X460066Y451600I-1J-612D01*
G01Y450600D01*
G02X459947Y450237I-611J-1D01*
G03Y449763I322J-237D01*
G02X460066Y449400I-492J-362D01*
G01Y448400D01*
G37*
G36*
G01X457566D02*
G02X456955Y447788I-611J-1D01*
G01X456155D01*
G02X455544Y448400I1J612D01*
G01Y449400D01*
G02X455663Y449763I611J1D01*
G03Y450237I-322J237D01*
G02X455544Y450600I492J362D01*
G01Y451600D01*
G02X456155Y452212I611J1D01*
G01X456955D01*
G02X457566Y451600I-1J-612D01*
G01Y450600D01*
G02X457447Y450237I-611J-1D01*
G03Y449763I322J-237D01*
G02X457566Y449400I-492J-362D01*
G01Y448400D01*
G37*
G36*
G01X453066D02*
G02X452455Y447788I-611J-1D01*
G01X451655D01*
G02X451044Y448400I1J612D01*
G01Y449400D01*
G02X451163Y449763I611J1D01*
G03Y450237I-322J237D01*
G02X451044Y450600I492J362D01*
G01Y451600D01*
G02X451655Y452212I611J1D01*
G01X452455D01*
G02X453066Y451600I-1J-612D01*
G01Y450600D01*
G02X452947Y450237I-611J-1D01*
G03Y449763I322J-237D01*
G02X453066Y449400I-492J-362D01*
G01Y448400D01*
G37*
G36*
G01X450566D02*
G02X449955Y447788I-611J-1D01*
G01X449155D01*
G02X448544Y448400I1J612D01*
G01Y449400D01*
G02X448663Y449763I611J1D01*
G03Y450237I-322J237D01*
G02X448544Y450600I492J362D01*
G01Y451600D01*
G02X449155Y452212I611J1D01*
G01X449955D01*
G02X450566Y451600I-1J-612D01*
G01Y450600D01*
G02X450447Y450237I-611J-1D01*
G03Y449763I322J-237D01*
G02X450566Y449400I-492J-362D01*
G01Y448400D01*
G37*
G36*
G01X446066D02*
G02X445455Y447788I-611J-1D01*
G01X444655D01*
G02X444044Y448400I1J612D01*
G01Y449400D01*
G02X444163Y449763I611J1D01*
G03Y450237I-322J237D01*
G02X444044Y450600I492J362D01*
G01Y451600D01*
G02X444655Y452212I611J1D01*
G01X445455D01*
G02X446066Y451600I-1J-612D01*
G01Y450600D01*
G02X445947Y450237I-611J-1D01*
G03Y449763I322J-237D01*
G02X446066Y449400I-492J-362D01*
G01Y448400D01*
G37*
G36*
G01X443566D02*
G02X442955Y447788I-611J-1D01*
G01X442155D01*
G02X441544Y448400I1J612D01*
G01Y449400D01*
G02X441663Y449763I611J1D01*
G03Y450237I-322J237D01*
G02X441544Y450600I492J362D01*
G01Y451600D01*
G02X442155Y452212I611J1D01*
G01X442955D01*
G02X443566Y451600I-1J-612D01*
G01Y450600D01*
G02X443447Y450237I-611J-1D01*
G03Y449763I322J-237D01*
G02X443566Y449400I-492J-362D01*
G01Y448400D01*
G37*
G36*
G01X439066D02*
G02X438455Y447788I-611J-1D01*
G01X437655D01*
G02X437044Y448400I1J612D01*
G01Y449400D01*
G02X437163Y449763I611J1D01*
G03Y450237I-322J237D01*
G02X437044Y450600I492J362D01*
G01Y451600D01*
G02X437655Y452212I611J1D01*
G01X438455D01*
G02X439066Y451600I-1J-612D01*
G01Y450600D01*
G02X438947Y450237I-611J-1D01*
G03Y449763I322J-237D01*
G02X439066Y449400I-492J-362D01*
G01Y448400D01*
G37*
G36*
G01X436566D02*
G02X435955Y447788I-611J-1D01*
G01X435155D01*
G02X434544Y448400I1J612D01*
G01Y449400D01*
G02X434663Y449763I611J1D01*
G03Y450237I-322J237D01*
G02X434544Y450600I492J362D01*
G01Y451600D01*
G02X435155Y452212I611J1D01*
G01X435955D01*
G02X436566Y451600I-1J-612D01*
G01Y450600D01*
G02X436447Y450237I-611J-1D01*
G03Y449763I322J-237D01*
G02X436566Y449400I-492J-362D01*
G01Y448400D01*
G37*
G36*
G01X432066D02*
G02X431455Y447788I-611J-1D01*
G01X430655D01*
G02X430044Y448400I1J612D01*
G01Y449400D01*
G02X430163Y449763I611J1D01*
G03Y450237I-322J237D01*
G02X430044Y450600I492J362D01*
G01Y451600D01*
G02X430655Y452212I611J1D01*
G01X431455D01*
G02X432066Y451600I-1J-612D01*
G01Y450600D01*
G02X431947Y450237I-611J-1D01*
G03Y449763I322J-237D01*
G02X432066Y449400I-492J-362D01*
G01Y448400D01*
G37*
G36*
G01X429566D02*
G02X428955Y447788I-611J-1D01*
G01X428155D01*
G02X427544Y448400I1J612D01*
G01Y449400D01*
G02X427663Y449763I611J1D01*
G03Y450237I-322J237D01*
G02X427544Y450600I492J362D01*
G01Y451600D01*
G02X428155Y452212I611J1D01*
G01X428955D01*
G02X429566Y451600I-1J-612D01*
G01Y450600D01*
G02X429447Y450237I-611J-1D01*
G03Y449763I322J-237D01*
G02X429566Y449400I-492J-362D01*
G01Y448400D01*
G37*
G36*
G01X425066D02*
G02X424455Y447788I-611J-1D01*
G01X423655D01*
G02X423044Y448400I1J612D01*
G01Y449400D01*
G02X423163Y449763I611J1D01*
G03Y450237I-322J237D01*
G02X423044Y450600I492J362D01*
G01Y451600D01*
G02X423655Y452212I611J1D01*
G01X424455D01*
G02X425066Y451600I-1J-612D01*
G01Y450600D01*
G02X424947Y450237I-611J-1D01*
G03Y449763I322J-237D01*
G02X425066Y449400I-492J-362D01*
G01Y448400D01*
G37*
G36*
G01X422566D02*
G02X421955Y447788I-611J-1D01*
G01X421155D01*
G02X420544Y448400I1J612D01*
G01Y449400D01*
G02X420663Y449763I611J1D01*
G03Y450237I-322J237D01*
G02X420544Y450600I492J362D01*
G01Y451600D01*
G02X421155Y452212I611J1D01*
G01X421955D01*
G02X422566Y451600I-1J-612D01*
G01Y450600D01*
G02X422447Y450237I-611J-1D01*
G03Y449763I322J-237D01*
G02X422566Y449400I-492J-362D01*
G01Y448400D01*
G37*
G36*
G01X418066D02*
G02X417455Y447788I-611J-1D01*
G01X416655D01*
G02X416044Y448400I1J612D01*
G01Y449400D01*
G02X416163Y449763I611J1D01*
G03Y450237I-322J237D01*
G02X416044Y450600I492J362D01*
G01Y451600D01*
G02X416655Y452212I611J1D01*
G01X417455D01*
G02X418066Y451600I-1J-612D01*
G01Y450600D01*
G02X417947Y450237I-611J-1D01*
G03Y449763I322J-237D01*
G02X418066Y449400I-492J-362D01*
G01Y448400D01*
G37*
G36*
G01X415566D02*
G02X414955Y447788I-611J-1D01*
G01X414155D01*
G02X413544Y448400I1J612D01*
G01Y449400D01*
G02X413663Y449763I611J1D01*
G03Y450237I-322J237D01*
G02X413544Y450600I492J362D01*
G01Y451600D01*
G02X414155Y452212I611J1D01*
G01X414955D01*
G02X415566Y451600I-1J-612D01*
G01Y450600D01*
G02X415447Y450237I-611J-1D01*
G03Y449763I322J-237D01*
G02X415566Y449400I-492J-362D01*
G01Y448400D01*
G37*
G36*
G01X411066D02*
G02X410455Y447788I-611J-1D01*
G01X409655D01*
G02X409044Y448400I1J612D01*
G01Y449400D01*
G02X409163Y449763I611J1D01*
G03Y450237I-322J237D01*
G02X409044Y450600I492J362D01*
G01Y451600D01*
G02X409655Y452212I611J1D01*
G01X410455D01*
G02X411066Y451600I-1J-612D01*
G01Y450600D01*
G02X410947Y450237I-611J-1D01*
G03Y449763I322J-237D01*
G02X411066Y449400I-492J-362D01*
G01Y448400D01*
G37*
G36*
G01X408566D02*
G02X407955Y447788I-611J-1D01*
G01X407155D01*
G02X406544Y448400I1J612D01*
G01Y449400D01*
G02X406663Y449763I611J1D01*
G03Y450237I-322J237D01*
G02X406544Y450600I492J362D01*
G01Y451600D01*
G02X407155Y452212I611J1D01*
G01X407955D01*
G02X408566Y451600I-1J-612D01*
G01Y450600D01*
G02X408447Y450237I-611J-1D01*
G03Y449763I322J-237D01*
G02X408566Y449400I-492J-362D01*
G01Y448400D01*
G37*
G36*
G01X404066D02*
G02X403455Y447788I-611J-1D01*
G01X402655D01*
G02X402044Y448400I1J612D01*
G01Y449400D01*
G02X402163Y449763I611J1D01*
G03Y450237I-322J237D01*
G02X402044Y450600I492J362D01*
G01Y451600D01*
G02X402655Y452212I611J1D01*
G01X403455D01*
G02X404066Y451600I-1J-612D01*
G01Y450600D01*
G02X403947Y450237I-611J-1D01*
G03Y449763I322J-237D01*
G02X404066Y449400I-492J-362D01*
G01Y448400D01*
G37*
G36*
G01X401566D02*
G02X400955Y447788I-611J-1D01*
G01X400155D01*
G02X399544Y448400I1J612D01*
G01Y449400D01*
G02X399663Y449763I611J1D01*
G03Y450237I-322J237D01*
G02X399544Y450600I492J362D01*
G01Y451600D01*
G02X400155Y452212I611J1D01*
G01X400955D01*
G02X401566Y451600I-1J-612D01*
G01Y450600D01*
G02X401447Y450237I-611J-1D01*
G03Y449763I322J-237D01*
G02X401566Y449400I-492J-362D01*
G01Y448400D01*
G37*
G36*
G01X469326Y408344D02*
Y405437D01*
X469336Y405405D01*
G02X466492I-1422J-483D01*
G01X466502Y405437D01*
Y408344D01*
X466492Y408376D01*
G02X469336I1422J483D01*
G01X469326Y408344D01*
G37*
G36*
G01X465388D02*
Y405437D01*
X465399Y405405D01*
G02X462555I-1422J-483D01*
G01X462566Y405437D01*
Y408344D01*
X462555Y408376D01*
G02X465399I1422J483D01*
G01X465388Y408344D01*
G37*
G36*
G01X449638D02*
Y405437D01*
X449649Y405405D01*
G02X446805I-1422J-483D01*
G01X446816Y405437D01*
Y408344D01*
X446805Y408376D01*
G02X449649I1422J483D01*
G01X449638Y408344D01*
G37*
G36*
G01X445702D02*
Y405437D01*
X445712Y405405D01*
G02X442868I-1422J-483D01*
G01X442878Y405437D01*
Y408344D01*
X442868Y408376D01*
G02X445712I1422J483D01*
G01X445702Y408344D01*
G37*
G36*
G01X441764D02*
Y405437D01*
X441775Y405405D01*
G02X438931I-1422J-483D01*
G01X438942Y405437D01*
Y408344D01*
X438931Y408376D01*
G02X441775I1422J483D01*
G01X441764Y408344D01*
G37*
G36*
G01X437828D02*
Y405437D01*
X437838Y405405D01*
G02X434994I-1422J-483D01*
G01X435004Y405437D01*
Y408344D01*
X434994Y408376D01*
G02X437838I1422J483D01*
G01X437828Y408344D01*
G37*
G36*
G01X433890D02*
Y405437D01*
X433901Y405405D01*
G02X431057I-1422J-483D01*
G01X431068Y405437D01*
Y408344D01*
X431057Y408376D01*
G02X433901I1422J483D01*
G01X433890Y408344D01*
G37*
G36*
G01X429954D02*
Y405437D01*
X429964Y405405D01*
G02X427120I-1422J-483D01*
G01X427130Y405437D01*
Y408344D01*
X427120Y408376D01*
G02X429964I1422J483D01*
G01X429954Y408344D01*
G37*
G36*
G01X426016D02*
Y405437D01*
X426027Y405405D01*
G02X423183I-1422J-483D01*
G01X423194Y405437D01*
Y408344D01*
X423183Y408376D01*
G02X426027I1422J483D01*
G01X426016Y408344D01*
G37*
G36*
G01X422080D02*
Y405437D01*
X422090Y405405D01*
G02X419246I-1422J-483D01*
G01X419256Y405437D01*
Y408344D01*
X419246Y408376D01*
G02X422090I1422J483D01*
G01X422080Y408344D01*
G37*
G36*
G01X457634Y408268D02*
Y405398D01*
X457645Y405366D01*
G02X454801I-1422J-483D01*
G01X454812Y405398D01*
Y408268D01*
X454801Y408300D01*
G02X457645I1422J483D01*
G01X457634Y408268D01*
G37*
G36*
G01X453634D02*
Y405398D01*
X453645Y405366D01*
G02X450801I-1422J-483D01*
G01X450812Y405398D01*
Y408268D01*
X450801Y408300D01*
G02X453645I1422J483D01*
G01X453634Y408268D01*
G37*
G36*
G01X519376Y387860D02*
G02X518765Y387248I-611J-1D01*
G01X517965D01*
G02X517354Y387860I1J612D01*
G01Y388860D01*
G02X517473Y389223I611J1D01*
G03Y389697I-322J237D01*
G02X517354Y390060I492J362D01*
G01Y391060D01*
G02X517965Y391672I611J1D01*
G01X518765D01*
G02X519376Y391060I-1J-612D01*
G01Y390060D01*
G02X519257Y389697I-611J-1D01*
G03Y389223I322J-237D01*
G02X519376Y388860I-492J-362D01*
G01Y387860D01*
G37*
G36*
G01X516876D02*
G02X516265Y387248I-611J-1D01*
G01X515465D01*
G02X514854Y387860I1J612D01*
G01Y388860D01*
G02X514973Y389223I611J1D01*
G03Y389697I-322J237D01*
G02X514854Y390060I492J362D01*
G01Y391060D01*
G02X515465Y391672I611J1D01*
G01X516265D01*
G02X516876Y391060I-1J-612D01*
G01Y390060D01*
G02X516757Y389697I-611J-1D01*
G03Y389223I322J-237D01*
G02X516876Y388860I-492J-362D01*
G01Y387860D01*
G37*
G36*
G01X540012Y387400D02*
G02X539400Y386788I-612J0D01*
G01X538600D01*
G02X537988Y387400I0J612D01*
G01Y388400D01*
G02X538108Y388763I612J-1D01*
G03Y389237I-322J237D01*
G02X537988Y389600I492J364D01*
G01Y390600D01*
G02X538600Y391212I612J0D01*
G01X539400D01*
G02X540012Y390600I0J-612D01*
G01Y389600D01*
G02X539892Y389237I-612J1D01*
G03Y388763I322J-237D01*
G02X540012Y388400I-492J-364D01*
G01Y387400D01*
G37*
G36*
G01X537512D02*
G02X536900Y386788I-612J0D01*
G01X536100D01*
G02X535488Y387400I0J612D01*
G01Y388400D01*
G02X535608Y388763I612J-1D01*
G03Y389237I-322J237D01*
G02X535488Y389600I492J364D01*
G01Y390600D01*
G02X536100Y391212I612J0D01*
G01X536900D01*
G02X537512Y390600I0J-612D01*
G01Y389600D01*
G02X537392Y389237I-612J1D01*
G03Y388763I322J-237D01*
G02X537512Y388400I-492J-364D01*
G01Y387400D01*
G37*
G36*
G01X533066D02*
G02X532455Y386788I-611J-1D01*
G01X531655D01*
G02X531044Y387400I1J612D01*
G01Y388400D01*
G02X531163Y388763I611J1D01*
G03Y389237I-322J237D01*
G02X531044Y389600I492J362D01*
G01Y390600D01*
G02X531655Y391212I611J1D01*
G01X532455D01*
G02X533066Y390600I-1J-612D01*
G01Y389600D01*
G02X532947Y389237I-611J-1D01*
G03Y388763I322J-237D01*
G02X533066Y388400I-492J-362D01*
G01Y387400D01*
G37*
G36*
G01X530566D02*
G02X529955Y386788I-611J-1D01*
G01X529155D01*
G02X528544Y387400I1J612D01*
G01Y388400D01*
G02X528663Y388763I611J1D01*
G03Y389237I-322J237D01*
G02X528544Y389600I492J362D01*
G01Y390600D01*
G02X529155Y391212I611J1D01*
G01X529955D01*
G02X530566Y390600I-1J-612D01*
G01Y389600D01*
G02X530447Y389237I-611J-1D01*
G03Y388763I322J-237D01*
G02X530566Y388400I-492J-362D01*
G01Y387400D01*
G37*
G36*
G01X526066D02*
G02X525455Y386788I-611J-1D01*
G01X524655D01*
G02X524044Y387400I1J612D01*
G01Y388400D01*
G02X524163Y388763I611J1D01*
G03Y389237I-322J237D01*
G02X524044Y389600I492J362D01*
G01Y390600D01*
G02X524655Y391212I611J1D01*
G01X525455D01*
G02X526066Y390600I-1J-612D01*
G01Y389600D01*
G02X525947Y389237I-611J-1D01*
G03Y388763I322J-237D01*
G02X526066Y388400I-492J-362D01*
G01Y387400D01*
G37*
G36*
G01X523566D02*
G02X522955Y386788I-611J-1D01*
G01X522155D01*
G02X521544Y387400I1J612D01*
G01Y388400D01*
G02X521663Y388763I611J1D01*
G03Y389237I-322J237D01*
G02X521544Y389600I492J362D01*
G01Y390600D01*
G02X522155Y391212I611J1D01*
G01X522955D01*
G02X523566Y390600I-1J-612D01*
G01Y389600D01*
G02X523447Y389237I-611J-1D01*
G03Y388763I322J-237D01*
G02X523566Y388400I-492J-362D01*
G01Y387400D01*
G37*
G36*
G01X71089Y390137D02*
G03X71345Y390581I-138J375D01*
G02X71328Y390773I1095J194D01*
G01Y396473D01*
G02X73552I1112J0D01*
G01Y390773D01*
G02X73378Y390176I-1111J0D01*
G03X73444Y389668I337J-214D01*
G02X73619Y389488I-1561J-1692D01*
G01X74347D01*
G02X74682Y389802I1734J-1514D01*
G03X74717Y390085I-122J159D01*
G02X74478Y390773I873J689D01*
G01Y396473D01*
G02X76702I1112J0D01*
G01Y390773D01*
G02X76646Y390425I-1112J0D01*
G03X76775Y390171I190J-63D01*
G02X74347Y386464I-692J-2195D01*
G01X73619D01*
G02X71089Y390137I-1736J1512D01*
G37*
G36*
G01X64410Y389404D02*
X64471Y389343D01*
X64713Y389350D01*
X64770Y389414D01*
G02X65077Y389698I1710J-1541D01*
G03X65178Y390216I-245J317D01*
G02X65028Y390773I962J558D01*
G01Y396473D01*
G02X67252I1112J0D01*
G01Y390773D01*
G02X67205Y390456I-1112J3D01*
G03X67425Y389976I383J-115D01*
G02X64856Y386248I-941J-2100D01*
G01X64795Y386309D01*
X64553Y386302D01*
X64496Y386238D01*
G02X61767Y389842I-1713J1538D01*
G03X61961Y390352I-176J359D01*
G02X61878Y390773I1029J422D01*
G01Y396473D01*
G02X64102I1112J0D01*
G01Y390773D01*
G02X63951Y390215I-1112J1D01*
G03X64073Y389683I346J-201D01*
G02X64410Y389404I-1293J-1905D01*
G37*
G36*
G01X45413Y389489D02*
G03X45946Y389490I266J299D01*
G02X46174Y389670I1538J-1713D01*
G03X46290Y390204I-227J329D01*
G02X46134Y390773I955J568D01*
G01Y396473D01*
G02X48356I1111J0D01*
G01Y390773D01*
G02X48278Y390361I-1112J-3D01*
G03X48476Y389853I371J-148D01*
G02X45953Y386056I-993J-2077D01*
G03X45420Y386055I-266J-299D01*
G02X42873Y389838I-1536J1714D01*
G03X43067Y390349I-176J359D01*
G02X42984Y390773I1028J421D01*
G01Y396473D01*
G02X45206I1111J0D01*
G01Y390773D01*
G02X45053Y390209I-1111J-1D01*
G03X45173Y389675I345J-203D01*
G02X45413Y389489I-1287J-1908D01*
G37*
G36*
G01X54774Y389339D02*
X54837Y389279D01*
X55066Y389292D01*
X55122Y389358D01*
G02X55571Y389768I1763J-1480D01*
G03X55701Y390275I-228J329D01*
G02X55584Y390773I1001J498D01*
G01Y396473D01*
G02X57806I1111J0D01*
G01Y390773D01*
G02X57745Y390408I-1111J-2D01*
G03X57939Y389921I378J-132D01*
G02X55291Y386213I-1056J-2045D01*
G01X55229Y386273D01*
X55000Y386260D01*
X54945Y386194D01*
G02X52309Y389805I-1762J1482D01*
G03X52524Y390334I-152J370D01*
G02X52434Y390773I1021J438D01*
G01Y396473D01*
G02X54656I1111J0D01*
G01Y390773D01*
G02X54437Y390110I-1111J-1D01*
G03X54525Y389546I321J-239D01*
G02X54774Y389339I-1343J-1869D01*
G37*
G36*
G01X484136Y370835D02*
X484168Y370825D01*
X487061Y370884D01*
X487092Y370895D01*
G02X487150Y368051I511J-1412D01*
G01X487118Y368061D01*
X484225Y368002D01*
X484194Y367991D01*
G02X484136Y370835I-511J1412D01*
G37*
G36*
G01X485085Y364979D02*
X485074Y364948D01*
Y362127D01*
X485084Y362096D01*
G02X482240Y362097I-1422J-483D01*
G01X482251Y362128D01*
Y364949D01*
X482241Y364980D01*
G02X485085Y364979I1422J483D01*
G37*
G36*
G01X522012Y361968D02*
Y359469D01*
X522022Y359438D01*
G02X518996Y358385I-1522J-501D01*
G03X518757Y358509I-188J-69D01*
G02X518600Y358488I-159J591D01*
G01X517600D01*
G02X517237Y358608I1J612D01*
G03X516763I-237J-322D01*
G02X516400Y358488I-364J492D01*
G01X515400D01*
G02X514788Y359100I0J612D01*
G01Y359900D01*
G02X515400Y360512I612J0D01*
G01X516400D01*
G02X516763Y360392I-1J-612D01*
G03X517237I237J322D01*
G02X517600Y360512I364J-492D01*
G01X518600D01*
G02X518742Y360495I-1J-612D01*
G01X518765Y360489D01*
X518988D01*
Y361011D01*
X518765D01*
X518742Y361005D01*
G02X518600Y360988I-143J595D01*
G01X517600D01*
G02X517237Y361108I1J612D01*
G03X516763I-237J-322D01*
G02X516400Y360988I-364J492D01*
G01X515400D01*
G02X514788Y361600I0J612D01*
G01Y362400D01*
G02X515400Y363012I612J0D01*
G01X516400D01*
G02X516763Y362892I-1J-612D01*
G03X517237I237J322D01*
G02X517600Y363012I364J-492D01*
G01X518600D01*
G02X518774Y362986I-2J-612D01*
G03X519016Y363103I56J192D01*
G02X522022Y361999I1485J-602D01*
G01X522012Y361968D01*
G37*
G36*
G01X487084Y356264D02*
X484177D01*
X484145Y356254D01*
G02Y359098I-483J1422D01*
G01X484177Y359088D01*
X487084D01*
X487116Y359098D01*
G02Y356254I483J-1422D01*
G01X487084Y356264D01*
G37*
G36*
G01X516763Y355108D02*
G02X516400Y354988I-364J492D01*
G01X515400D01*
G02X514788Y355600I0J612D01*
G01Y356400D01*
G02X515400Y357012I612J0D01*
G01X516400D01*
G02X516763Y356892I-1J-612D01*
G03X517237I237J322D01*
G02X517600Y357012I364J-492D01*
G01X518600D01*
G02X519212Y356400I0J-612D01*
G01Y355600D01*
G02X518600Y354988I-612J0D01*
G01X517600D01*
G02X517237Y355108I1J612D01*
G03X516763I-237J-322D01*
G37*
G36*
G01X164909Y353198D02*
X164539D01*
X164480Y353134D01*
G02Y356284I-1679J1575D01*
G01X164539Y356220D01*
X164909D01*
X164968Y356284D01*
G02Y353134I1679J-1575D01*
G01X164909Y353198D01*
G37*
G36*
G01X153409D02*
X153039D01*
X152980Y353134D01*
G02Y356284I-1679J1575D01*
G01X153039Y356220D01*
X153409D01*
X153468Y356284D01*
G02Y353134I1679J-1575D01*
G01X153409Y353198D01*
G37*
G36*
G01X141409D02*
X141039D01*
X140980Y353134D01*
G02Y356284I-1679J1575D01*
G01X141039Y356220D01*
X141409D01*
X141468Y356284D01*
G02Y353134I1679J-1575D01*
G01X141409Y353198D01*
G37*
G36*
G01X129409D02*
X129039D01*
X128980Y353134D01*
G02Y356284I-1679J1575D01*
G01X129039Y356220D01*
X129409D01*
X129468Y356284D01*
G02Y353134I1679J-1575D01*
G01X129409Y353198D01*
G37*
G36*
G01X487084Y352328D02*
X484177D01*
X484145Y352317D01*
G02Y355161I-483J1422D01*
G01X484177Y355150D01*
X487084D01*
X487116Y355161D01*
G02Y352317I483J-1422D01*
G01X487084Y352328D01*
G37*
G36*
G01X528012Y356000D02*
Y353501D01*
X528022Y353470D01*
G02X524978I-1522J-501D01*
G01X524988Y353501D01*
Y356000D01*
X524978Y356031D01*
G02X528022I1522J501D01*
G01X528012Y356000D01*
G37*
G36*
G01X516763Y342608D02*
G02X516400Y342488I-364J492D01*
G01X515400D01*
G02X514788Y343100I0J612D01*
G01Y343900D01*
G02X515400Y344512I612J0D01*
G01X516400D01*
G02X516763Y344392I-1J-612D01*
G03X517237I237J322D01*
G02X517600Y344512I364J-492D01*
G01X518600D01*
G02X519212Y343900I0J-612D01*
G01Y343100D01*
G02X518600Y342488I-612J0D01*
G01X517600D01*
G02X517237Y342608I1J612D01*
G03X516763I-237J-322D01*
G37*
G36*
G01X1198147Y342875D02*
G03X1197613I-267J-298D01*
G02Y346301I-1538J1713D01*
G03X1198147I267J298D01*
G02Y342875I1538J-1713D01*
G37*
G36*
G01X528012Y346000D02*
Y343501D01*
X528022Y343470D01*
G02X524978I-1522J-501D01*
G01X524988Y343501D01*
Y346000D01*
X524978Y346031D01*
G02X528022I1522J501D01*
G01X528012Y346000D01*
G37*
G36*
G01X194386Y343719D02*
Y343349D01*
X194449Y343290D01*
G02X191299I-1575J-1679D01*
G01X191362Y343349D01*
Y343719D01*
X191299Y343778D01*
G02X194449I1575J1679D01*
G01X194386Y343719D01*
G37*
G36*
G01X515786Y333891D02*
G02X515423Y333772I-362J492D01*
G01X514423D01*
G02X513812Y334383I0J611D01*
G01Y335183D01*
G02X514423Y335794I611J0D01*
G01X515423D01*
G02X515786Y335675I1J-611D01*
G03X516260I237J322D01*
G02X516623Y335794I362J-492D01*
G01X517623D01*
G02X518234Y335183I0J-611D01*
G01Y334383D01*
G02X517623Y333772I-611J0D01*
G01X516623D01*
G02X516260Y333891I-1J611D01*
G03X515786I-237J-322D01*
G37*
G36*
G01X486937Y332441D02*
X486906Y332453D01*
X484094Y332615D01*
X484062Y332606D01*
G02X484225Y335446I-400J1448D01*
G01X484256Y335434D01*
X487068Y335272D01*
X487100Y335281D01*
G02X486937Y332441I400J-1448D01*
G37*
G36*
G01X526286Y331891D02*
G02X525923Y331772I-362J492D01*
G01X524923D01*
G02X524312Y332383I0J611D01*
G01Y333183D01*
G02X524923Y333794I611J0D01*
G01X525923D01*
G02X526286Y333675I1J-611D01*
G03X526760I237J322D01*
G02X527123Y333794I362J-492D01*
G01X528123D01*
G02X528734Y333183I0J-611D01*
G01Y332383D01*
G02X528123Y331772I-611J0D01*
G01X527123D01*
G02X526760Y331891I-1J611D01*
G03X526286I-237J-322D01*
G37*
G36*
G01X515786Y331391D02*
G02X515423Y331272I-362J492D01*
G01X514423D01*
G02X513812Y331883I0J611D01*
G01Y332683D01*
G02X514423Y333294I611J0D01*
G01X515423D01*
G02X515786Y333175I1J-611D01*
G03X516260I237J322D01*
G02X516623Y333294I362J-492D01*
G01X517623D01*
G02X518234Y332683I0J-611D01*
G01Y331883D01*
G02X517623Y331272I-611J0D01*
G01X516623D01*
G02X516260Y331391I-1J611D01*
G03X515786I-237J-322D01*
G37*
G36*
G01X526286Y329391D02*
G02X525923Y329272I-362J492D01*
G01X524923D01*
G02X524312Y329883I0J611D01*
G01Y330683D01*
G02X524923Y331294I611J0D01*
G01X525923D01*
G02X526286Y331175I1J-611D01*
G03X526760I237J322D01*
G02X527123Y331294I362J-492D01*
G01X528123D01*
G02X528734Y330683I0J-611D01*
G01Y329883D01*
G02X528123Y329272I-611J0D01*
G01X527123D01*
G02X526760Y329391I-1J611D01*
G03X526286I-237J-322D01*
G37*
G36*
G01X487084Y328706D02*
X484177D01*
X484145Y328695D01*
G02Y331539I-483J1422D01*
G01X484177Y331528D01*
X487084D01*
X487116Y331539D01*
G02Y328695I483J-1422D01*
G01X487084Y328706D01*
G37*
G36*
G01X194386Y332569D02*
Y332199D01*
X194449Y332140D01*
G02X191299I-1575J-1679D01*
G01X191362Y332199D01*
Y332569D01*
X191299Y332628D01*
G02X194449I1575J1679D01*
G01X194386Y332569D01*
G37*
G36*
G01X177884Y327238D02*
X177514D01*
X177455Y327174D01*
G02Y330324I-1679J1575D01*
G01X177514Y330260D01*
X177884D01*
X177943Y330324D01*
G02Y327174I1679J-1575D01*
G01X177884Y327238D01*
G37*
G36*
G01X166255Y327188D02*
X165885D01*
X165826Y327124D01*
G02Y330274I-1679J1575D01*
G01X165885Y330210D01*
X166255D01*
X166314Y330274D01*
G02Y327124I1679J-1575D01*
G01X166255Y327188D01*
G37*
G36*
G01X520286Y326391D02*
G02X519923Y326272I-362J492D01*
G01X518923D01*
G02X518312Y326883I0J611D01*
G01Y327683D01*
G02X518923Y328294I611J0D01*
G01X519923D01*
G02X520286Y328175I1J-611D01*
G03X520760I237J322D01*
G02X521123Y328294I362J-492D01*
G01X522123D01*
G02X522734Y327683I0J-611D01*
G01Y326883D01*
G02X522123Y326272I-611J0D01*
G01X521123D01*
G02X520760Y326391I-1J611D01*
G03X520286I-237J-322D01*
G37*
G36*
G01X487084Y324768D02*
X484177D01*
X484145Y324758D01*
G02Y327602I-483J1422D01*
G01X484177Y327592D01*
X487084D01*
X487116Y327602D01*
G02Y324758I483J-1422D01*
G01X487084Y324768D01*
G37*
G36*
G01X532970Y323988D02*
X530380D01*
X530349Y323978D01*
G02Y327022I-501J1522D01*
G01X530380Y327012D01*
X532970D01*
X533001Y327022D01*
G02Y323978I501J-1522D01*
G01X532970Y323988D01*
G37*
G36*
G01X520286Y323891D02*
G02X519923Y323772I-362J492D01*
G01X518923D01*
G02X518312Y324383I0J611D01*
G01Y325183D01*
G02X518923Y325794I611J0D01*
G01X519923D01*
G02X520286Y325675I1J-611D01*
G03X520760I237J322D01*
G02X521123Y325794I362J-492D01*
G01X522123D01*
G02X522734Y325183I0J-611D01*
G01Y324383D01*
G02X522123Y323772I-611J0D01*
G01X521123D01*
G02X520760Y323891I-1J611D01*
G03X520286I-237J-322D01*
G37*
G36*
G01X1171587Y322003D02*
G03X1171053I-267J-298D01*
G02Y325429I-1538J1713D01*
G03X1171587I267J298D01*
G02Y322003I1538J-1713D01*
G37*
G36*
G01X157386Y325219D02*
Y324849D01*
X157449Y324790D01*
G02X154299I-1575J-1679D01*
G01X154362Y324849D01*
Y325219D01*
X154299Y325278D01*
G02X157449I1575J1679D01*
G01X157386Y325219D01*
G37*
G36*
G01X538082Y319488D02*
X535492D01*
X535461Y319478D01*
G02Y322522I-501J1522D01*
G01X535492Y322512D01*
X538082D01*
X538113Y322522D01*
G02Y319478I501J-1522D01*
G01X538082Y319488D01*
G37*
G36*
G01X511468Y318488D02*
X509032D01*
X509001Y318478D01*
G02Y321522I-501J1522D01*
G01X509032Y321512D01*
X511468D01*
X511499Y321522D01*
G02Y318478I501J-1522D01*
G01X511468Y318488D01*
G37*
G36*
G01X1254788Y322854D02*
Y322146D01*
X1254844Y322088D01*
G02X1251510I-1667J-1588D01*
G01X1251566Y322146D01*
Y322854D01*
X1251510Y322912D01*
G02X1254844I1667J1588D01*
G01X1254788Y322854D01*
G37*
G36*
G01X526470Y317848D02*
X523880D01*
X523849Y317837D01*
G02Y320881I-501J1522D01*
G01X523880Y320870D01*
X526470D01*
X526501Y320881D01*
G02Y317837I501J-1522D01*
G01X526470Y317848D01*
G37*
G36*
G01X520294Y317877D02*
G02X519683Y317266I-611J0D01*
G01X518883D01*
G02X518272Y317877I0J611D01*
G01Y318877D01*
G02X518391Y319240I611J1D01*
G03Y319714I-322J237D01*
G02X518272Y320077I492J362D01*
G01Y321077D01*
G02X518883Y321688I611J0D01*
G01X519683D01*
G02X520294Y321077I0J-611D01*
G01Y320077D01*
G02X520175Y319714I-611J-1D01*
G03Y319240I322J-237D01*
G02X520294Y318877I-492J-362D01*
G01Y317877D01*
G37*
G36*
G01X517294D02*
G02X516683Y317266I-611J0D01*
G01X515883D01*
G02X515272Y317877I0J611D01*
G01Y318877D01*
G02X515391Y319240I611J1D01*
G03Y319714I-322J237D01*
G02X515272Y320077I492J362D01*
G01Y321077D01*
G02X515883Y321688I611J0D01*
G01X516683D01*
G02X517294Y321077I0J-611D01*
G01Y320077D01*
G02X517175Y319714I-611J-1D01*
G03Y319240I322J-237D01*
G02X517294Y318877I-492J-362D01*
G01Y317877D01*
G37*
G36*
G01X494571Y314440D02*
X491789D01*
X491758Y314430D01*
G02Y317474I-501J1522D01*
G01X491789Y317464D01*
X494571D01*
X494602Y317474D01*
G02Y314430I501J-1522D01*
G01X494571Y314440D01*
G37*
G36*
G01X502715Y312688D02*
X502345D01*
X502286Y312625D01*
G02Y315775I-1679J1575D01*
G01X502345Y315712D01*
X502715D01*
X502774Y315775D01*
G02Y312625I1679J-1575D01*
G01X502715Y312688D01*
G37*
G36*
G01X517968Y312488D02*
X517598D01*
X517539Y312425D01*
G02Y315575I-1679J1575D01*
G01X517598Y315512D01*
X517968D01*
X518027Y315575D01*
G02Y312425I1679J-1575D01*
G01X517968Y312488D01*
G37*
G36*
G01X157386Y316069D02*
Y315699D01*
X157449Y315640D01*
G02X154299I-1575J-1679D01*
G01X154362Y315699D01*
Y316069D01*
X154299Y316128D01*
G02X157449I1575J1679D01*
G01X157386Y316069D01*
G37*
G36*
G01X1157813Y314867D02*
G03Y314333I298J-267D01*
G02X1154387I-1713J-1538D01*
G03Y314867I-298J267D01*
G02X1157813I1713J1538D01*
G37*
G36*
G01X1251863Y310336D02*
X1251916Y310395D01*
X1251897Y311124D01*
X1251842Y311180D01*
G02X1255191Y311264I1635J1620D01*
G01X1255138Y311205D01*
X1255157Y310476D01*
X1255212Y310420D01*
G02X1251863Y310336I-1635J-1620D01*
G37*
G36*
G01X1166713Y306637D02*
G03Y306103I298J-267D01*
G02X1163287I-1713J-1538D01*
G03Y306637I-298J267D01*
G02X1166713I1713J1538D01*
G37*
G36*
G01X805070Y301738D02*
X804680D01*
X804621Y301675D01*
G02Y304825I-1679J1575D01*
G01X804680Y304762D01*
X805070D01*
X805129Y304825D01*
G02Y301675I1679J-1575D01*
G01X805070Y301738D01*
G37*
G36*
G01X789320D02*
X788930D01*
X788871Y301675D01*
G02Y304825I-1679J1575D01*
G01X788930Y304762D01*
X789320D01*
X789379Y304825D01*
G02Y301675I1679J-1575D01*
G01X789320Y301738D01*
G37*
G36*
G01X773575D02*
X773185D01*
X773126Y301675D01*
G02Y304825I-1679J1575D01*
G01X773185Y304762D01*
X773575D01*
X773634Y304825D01*
G02Y301675I1679J-1575D01*
G01X773575Y301738D01*
G37*
G36*
G01X757825D02*
X757435D01*
X757376Y301675D01*
G02Y304825I-1679J1575D01*
G01X757435Y304762D01*
X757825D01*
X757884Y304825D01*
G02Y301675I1679J-1575D01*
G01X757825Y301738D01*
G37*
G36*
G01X663335D02*
X662945D01*
X662886Y301675D01*
G02Y304825I-1679J1575D01*
G01X662945Y304762D01*
X663335D01*
X663394Y304825D01*
G02Y301675I1679J-1575D01*
G01X663335Y301738D01*
G37*
G36*
G01X647585D02*
X647195D01*
X647136Y301675D01*
G02Y304825I-1679J1575D01*
G01X647195Y304762D01*
X647585D01*
X647644Y304825D01*
G02Y301675I1679J-1575D01*
G01X647585Y301738D01*
G37*
G36*
G01X631840D02*
X631450D01*
X631391Y301675D01*
G02Y304825I-1679J1575D01*
G01X631450Y304762D01*
X631840D01*
X631899Y304825D01*
G02Y301675I1679J-1575D01*
G01X631840Y301738D01*
G37*
G36*
G01X616090D02*
X615700D01*
X615641Y301675D01*
G02Y304825I-1679J1575D01*
G01X615700Y304762D01*
X616090D01*
X616149Y304825D01*
G02Y301675I1679J-1575D01*
G01X616090Y301738D01*
G37*
G36*
G01X1262188Y298322D02*
Y297748D01*
X1262244Y297690D01*
G02X1258910I-1667J-1588D01*
G01X1258966Y297748D01*
Y298322D01*
X1258910Y298380D01*
G02X1262244I1667J1588D01*
G01X1262188Y298322D01*
G37*
G36*
G01X211995Y293398D02*
X211625D01*
X211566Y293334D01*
G02Y296484I-1679J1575D01*
G01X211625Y296420D01*
X211995D01*
X212054Y296484D01*
G02Y293334I1679J-1575D01*
G01X211995Y293398D01*
G37*
G36*
G01X202547D02*
X202177D01*
X202118Y293334D01*
G02Y296484I-1679J1575D01*
G01X202177Y296420D01*
X202547D01*
X202606Y296484D01*
G02Y293334I1679J-1575D01*
G01X202547Y293398D01*
G37*
G36*
G01X177350D02*
X176980D01*
X176921Y293334D01*
G02Y296484I-1679J1575D01*
G01X176980Y296420D01*
X177350D01*
X177409Y296484D01*
G02Y293334I1679J-1575D01*
G01X177350Y293398D01*
G37*
G36*
G01X167901Y292798D02*
X167531D01*
X167472Y292734D01*
G02Y295884I-1679J1575D01*
G01X167531Y295820D01*
X167901D01*
X167960Y295884D01*
G02Y292734I1679J-1575D01*
G01X167901Y292798D01*
G37*
G36*
G01X1172039Y288614D02*
X1171515D01*
X1171456Y288550D01*
G02Y291700I-1679J1575D01*
G01X1171515Y291636D01*
X1172039D01*
X1172098Y291700D01*
G02Y288550I1679J-1575D01*
G01X1172039Y288614D01*
G37*
G36*
G01X1191005Y288288D02*
X1190615D01*
X1190556Y288225D01*
G02Y291375I-1679J1575D01*
G01X1190615Y291312D01*
X1191005D01*
X1191064Y291375D01*
G02Y288225I1679J-1575D01*
G01X1191005Y288288D01*
G37*
G36*
G01X1252288Y285854D02*
Y285146D01*
X1252344Y285088D01*
G02X1249010I-1667J-1588D01*
G01X1249066Y285146D01*
Y285854D01*
X1249010Y285912D01*
G02X1252344I1667J1588D01*
G01X1252288Y285854D01*
G37*
G36*
G01X1256456Y270695D02*
Y270305D01*
X1256519Y270246D01*
G02X1253369I-1575J-1679D01*
G01X1253432Y270305D01*
Y270695D01*
X1253369Y270754D01*
G02X1256519I1575J1679D01*
G01X1256456Y270695D01*
G37*
G36*
G01X340303Y177108D02*
G02X339940Y176988I-364J492D01*
G01X338940D01*
G02X338328Y177600I0J612D01*
G01Y178400D01*
G02X338940Y179012I612J0D01*
G01X339940D01*
G02X340303Y178892I-1J-612D01*
G03X340777I237J322D01*
G02X341140Y179012I364J-492D01*
G01X342140D01*
G02X342752Y178400I0J-612D01*
G01Y177600D01*
G02X342140Y176988I-612J0D01*
G01X341140D01*
G02X340777Y177108I1J612D01*
G03X340303I-237J-322D01*
G37*
G36*
G01Y174608D02*
G02X339940Y174488I-364J492D01*
G01X338940D01*
G02X338328Y175100I0J612D01*
G01Y175900D01*
G02X338940Y176512I612J0D01*
G01X339940D01*
G02X340303Y176392I-1J-612D01*
G03X340777I237J322D01*
G02X341140Y176512I364J-492D01*
G01X342140D01*
G02X342752Y175900I0J-612D01*
G01Y175100D01*
G02X342140Y174488I-612J0D01*
G01X341140D01*
G02X340777Y174608I1J612D01*
G03X340303I-237J-322D01*
G37*
G36*
G01Y170608D02*
G02X339940Y170488I-364J492D01*
G01X338940D01*
G02X338328Y171100I0J612D01*
G01Y171900D01*
G02X338940Y172512I612J0D01*
G01X339940D01*
G02X340303Y172392I-1J-612D01*
G03X340777I237J322D01*
G02X341140Y172512I364J-492D01*
G01X342140D01*
G02X342752Y171900I0J-612D01*
G01Y171100D01*
G02X342140Y170488I-612J0D01*
G01X341140D01*
G02X340777Y170608I1J612D01*
G03X340303I-237J-322D01*
G37*
G36*
G01Y168108D02*
G02X339940Y167988I-364J492D01*
G01X338940D01*
G02X338328Y168600I0J612D01*
G01Y169400D01*
G02X338940Y170012I612J0D01*
G01X339940D01*
G02X340303Y169892I-1J-612D01*
G03X340777I237J322D01*
G02X341140Y170012I364J-492D01*
G01X342140D01*
G02X342752Y169400I0J-612D01*
G01Y168600D01*
G02X342140Y167988I-612J0D01*
G01X341140D01*
G02X340777Y168108I1J612D01*
G03X340303I-237J-322D01*
G37*
G36*
G01Y164108D02*
G02X339940Y163988I-364J492D01*
G01X338940D01*
G02X338328Y164600I0J612D01*
G01Y165400D01*
G02X338940Y166012I612J0D01*
G01X339940D01*
G02X340303Y165892I-1J-612D01*
G03X340777I237J322D01*
G02X341140Y166012I364J-492D01*
G01X342140D01*
G02X342752Y165400I0J-612D01*
G01Y164600D01*
G02X342140Y163988I-612J0D01*
G01X341140D01*
G02X340777Y164108I1J612D01*
G03X340303I-237J-322D01*
G37*
G36*
G01X309166Y162288D02*
X306384D01*
X306353Y162278D01*
G02Y165322I-501J1522D01*
G01X306384Y165312D01*
X309166D01*
X309197Y165322D01*
G02Y162278I501J-1522D01*
G01X309166Y162288D01*
G37*
G36*
G01X340303Y161608D02*
G02X339940Y161488I-364J492D01*
G01X338940D01*
G02X338328Y162100I0J612D01*
G01Y162900D01*
G02X338940Y163512I612J0D01*
G01X339940D01*
G02X340303Y163392I-1J-612D01*
G03X340777I237J322D01*
G02X341140Y163512I364J-492D01*
G01X342140D01*
G02X342752Y162900I0J-612D01*
G01Y162100D01*
G02X342140Y161488I-612J0D01*
G01X341140D01*
G02X340777Y161608I1J612D01*
G03X340303I-237J-322D01*
G37*
G36*
G01Y157608D02*
G02X339940Y157488I-364J492D01*
G01X338940D01*
G02X338328Y158100I0J612D01*
G01Y158900D01*
G02X338940Y159512I612J0D01*
G01X339940D01*
G02X340303Y159392I-1J-612D01*
G03X340777I237J322D01*
G02X341140Y159512I364J-492D01*
G01X342140D01*
G02X342752Y158900I0J-612D01*
G01Y158100D01*
G02X342140Y157488I-612J0D01*
G01X341140D01*
G02X340777Y157608I1J612D01*
G03X340303I-237J-322D01*
G37*
G36*
G01Y155108D02*
G02X339940Y154988I-364J492D01*
G01X338940D01*
G02X338328Y155600I0J612D01*
G01Y156400D01*
G02X338940Y157012I612J0D01*
G01X339940D01*
G02X340303Y156892I-1J-612D01*
G03X340777I237J322D01*
G02X341140Y157012I364J-492D01*
G01X342140D01*
G02X342752Y156400I0J-612D01*
G01Y155600D01*
G02X342140Y154988I-612J0D01*
G01X341140D01*
G02X340777Y155108I1J612D01*
G03X340303I-237J-322D01*
G37*
G36*
G01X316716Y154488D02*
X313934D01*
X313903Y154478D01*
G02Y157522I-501J1522D01*
G01X313934Y157512D01*
X316716D01*
X316747Y157522D01*
G02Y154478I501J-1522D01*
G01X316716Y154488D01*
G37*
G36*
G01X340303Y151108D02*
G02X339940Y150988I-364J492D01*
G01X338940D01*
G02X338328Y151600I0J612D01*
G01Y152400D01*
G02X338940Y153012I612J0D01*
G01X339940D01*
G02X340303Y152892I-1J-612D01*
G03X340777I237J322D01*
G02X341140Y153012I364J-492D01*
G01X342140D01*
G02X342752Y152400I0J-612D01*
G01Y151600D01*
G02X342140Y150988I-612J0D01*
G01X341140D01*
G02X340777Y151108I1J612D01*
G03X340303I-237J-322D01*
G37*
G36*
G01Y148608D02*
G02X339940Y148488I-364J492D01*
G01X338940D01*
G02X338328Y149100I0J612D01*
G01Y149900D01*
G02X338940Y150512I612J0D01*
G01X339940D01*
G02X340303Y150392I-1J-612D01*
G03X340777I237J322D01*
G02X341140Y150512I364J-492D01*
G01X342140D01*
G02X342752Y149900I0J-612D01*
G01Y149100D01*
G02X342140Y148488I-612J0D01*
G01X341140D01*
G02X340777Y148608I1J612D01*
G03X340303I-237J-322D01*
G37*
G36*
G01X327934Y151975D02*
Y149476D01*
X327944Y149445D01*
G02X324900I-1522J-501D01*
G01X324910Y149476D01*
Y151975D01*
X324900Y152006D01*
G02X327944I1522J501D01*
G01X327934Y151975D01*
G37*
G36*
G01X329512Y149097D02*
X329522Y149127D01*
X329606Y152153D01*
X329597Y152183D01*
G02X332457Y152104I1443J418D01*
G01X332447Y152074D01*
X332363Y149048D01*
X332372Y149018D01*
G02X329512Y149097I-1443J-418D01*
G37*
G36*
G01X340303Y144608D02*
G02X339940Y144488I-364J492D01*
G01X338940D01*
G02X338328Y145100I0J612D01*
G01Y145900D01*
G02X338940Y146512I612J0D01*
G01X339940D01*
G02X340303Y146392I-1J-612D01*
G03X340777I237J322D01*
G02X341140Y146512I364J-492D01*
G01X342140D01*
G02X342752Y145900I0J-612D01*
G01Y145100D01*
G02X342140Y144488I-612J0D01*
G01X341140D01*
G02X340777Y144608I1J612D01*
G03X340303I-237J-322D01*
G37*
G36*
G01X303145Y142816D02*
X301567D01*
G02Y145840I-1736J1512D01*
G01X303145D01*
X303176Y145850D01*
G02Y142806I501J-1522D01*
G01X303145Y142816D01*
G37*
G36*
G01X340303Y142108D02*
G02X339940Y141988I-364J492D01*
G01X338940D01*
G02X338328Y142600I0J612D01*
G01Y143400D01*
G02X338940Y144012I612J0D01*
G01X339940D01*
G02X340303Y143892I-1J-612D01*
G03X340777I237J322D01*
G02X341140Y144012I364J-492D01*
G01X342140D01*
G02X342752Y143400I0J-612D01*
G01Y142600D01*
G02X342140Y141988I-612J0D01*
G01X341140D01*
G02X340777Y142108I1J612D01*
G03X340303I-237J-322D01*
G37*
G36*
G01X321312Y146366D02*
Y143584D01*
X321322Y143553D01*
G02X318278I-1522J-501D01*
G01X318288Y143584D01*
Y146366D01*
X318278Y146397D01*
G02X321322I1522J501D01*
G01X321312Y146366D01*
G37*
G36*
G01X340303Y138108D02*
G02X339940Y137988I-364J492D01*
G01X338940D01*
G02X338328Y138600I0J612D01*
G01Y139400D01*
G02X338940Y140012I612J0D01*
G01X339940D01*
G02X340303Y139892I-1J-612D01*
G03X340777I237J322D01*
G02X341140Y140012I364J-492D01*
G01X342140D01*
G02X342752Y139400I0J-612D01*
G01Y138600D01*
G02X342140Y137988I-612J0D01*
G01X341140D01*
G02X340777Y138108I1J612D01*
G03X340303I-237J-322D01*
G37*
G36*
G01Y135608D02*
G02X339940Y135488I-364J492D01*
G01X338940D01*
G02X338328Y136100I0J612D01*
G01Y136900D01*
G02X338940Y137512I612J0D01*
G01X339940D01*
G02X340303Y137392I-1J-612D01*
G03X340777I237J322D01*
G02X341140Y137512I364J-492D01*
G01X342140D01*
G02X342752Y136900I0J-612D01*
G01Y136100D01*
G02X342140Y135488I-612J0D01*
G01X341140D01*
G02X340777Y135608I1J612D01*
G03X340303I-237J-322D01*
G37*
G36*
G01X328612Y139325D02*
Y136826D01*
X328622Y136795D01*
G02X325578I-1522J-501D01*
G01X325588Y136826D01*
Y139325D01*
X325578Y139356D01*
G02X328622I1522J501D01*
G01X328612Y139325D01*
G37*
G36*
G01X340303Y131608D02*
G02X339940Y131488I-364J492D01*
G01X338940D01*
G02X338328Y132100I0J612D01*
G01Y132900D01*
G02X338940Y133512I612J0D01*
G01X339940D01*
G02X340303Y133392I-1J-612D01*
G03X340777I237J322D01*
G02X341140Y133512I364J-492D01*
G01X342140D01*
G02X342752Y132900I0J-612D01*
G01Y132100D01*
G02X342140Y131488I-612J0D01*
G01X341140D01*
G02X340777Y131608I1J612D01*
G03X340303I-237J-322D01*
G37*
G36*
G01Y129108D02*
G02X339940Y128988I-364J492D01*
G01X338940D01*
G02X338328Y129600I0J612D01*
G01Y130400D01*
G02X338940Y131012I612J0D01*
G01X339940D01*
G02X340303Y130892I-1J-612D01*
G03X340777I237J322D01*
G02X341140Y131012I364J-492D01*
G01X342140D01*
G02X342752Y130400I0J-612D01*
G01Y129600D01*
G02X342140Y128988I-612J0D01*
G01X341140D01*
G02X340777Y129108I1J612D01*
G03X340303I-237J-322D01*
G37*
G36*
G01X336112Y132499D02*
Y130000D01*
X336122Y129969D01*
G02X333078I-1522J-501D01*
G01X333088Y130000D01*
Y132499D01*
X333078Y132530D01*
G02X336122I1522J501D01*
G01X336112Y132499D01*
G37*
G36*
G01X1092156Y124988D02*
X1091766D01*
X1091707Y124925D01*
G02Y128075I-1679J1575D01*
G01X1091766Y128012D01*
X1092156D01*
X1092215Y128075D01*
G02Y124925I1679J-1575D01*
G01X1092156Y124988D01*
G37*
G36*
G01X1072448Y40156D02*
X1069284D01*
G02Y46378I-2355J3111D01*
G01X1072448D01*
G02Y40156I2355J-3111D01*
G37*
G36*
G01X480978Y874288D02*
X479578D01*
G02X478766Y875100I0J812D01*
G01Y876500D01*
G02X479120Y877170I811J0D01*
G03Y877830I-226J330D01*
G02X478766Y878500I457J670D01*
G01Y879900D01*
G02X479578Y880712I812J0D01*
G01X480978D01*
G02X481790Y879900I0J-812D01*
G01Y878500D01*
G02X481436Y877830I-811J0D01*
G03Y877170I226J-330D01*
G02X481790Y876500I-457J-670D01*
G01Y875100D01*
G02X480978Y874288I-812J0D01*
G37*
G36*
G01X474478D02*
X473078D01*
G02X472266Y875100I0J812D01*
G01Y876500D01*
G02X472620Y877170I811J0D01*
G03Y877830I-226J330D01*
G02X472266Y878500I457J670D01*
G01Y879900D01*
G02X473078Y880712I812J0D01*
G01X474478D01*
G02X475290Y879900I0J-812D01*
G01Y878500D01*
G02X474936Y877830I-811J0D01*
G03Y877170I226J-330D01*
G02X475290Y876500I-457J-670D01*
G01Y875100D01*
G02X474478Y874288I-812J0D01*
G37*
G36*
G01X451478D02*
X450078D01*
G02X449266Y875100I0J812D01*
G01Y876500D01*
G02X449620Y877170I811J0D01*
G03Y877830I-226J330D01*
G02X449266Y878500I457J670D01*
G01Y879900D01*
G02X450078Y880712I812J0D01*
G01X451478D01*
G02X452290Y879900I0J-812D01*
G01Y878500D01*
G02X451936Y877830I-811J0D01*
G03Y877170I226J-330D01*
G02X452290Y876500I-457J-670D01*
G01Y875100D01*
G02X451478Y874288I-812J0D01*
G37*
G36*
G01X444978D02*
X443578D01*
G02X442766Y875100I0J812D01*
G01Y876500D01*
G02X443120Y877170I811J0D01*
G03Y877830I-226J330D01*
G02X442766Y878500I457J670D01*
G01Y879900D01*
G02X443578Y880712I812J0D01*
G01X444978D01*
G02X445790Y879900I0J-812D01*
G01Y878500D01*
G02X445436Y877830I-811J0D01*
G03Y877170I226J-330D01*
G02X445790Y876500I-457J-670D01*
G01Y875100D01*
G02X444978Y874288I-812J0D01*
G37*
G36*
G01X476478Y803788D02*
X475078D01*
G02X474266Y804600I0J812D01*
G01Y806000D01*
G02X474620Y806670I811J0D01*
G03Y807330I-226J330D01*
G02X474266Y808000I457J670D01*
G01Y809400D01*
G02X475078Y810212I812J0D01*
G01X476478D01*
G02X477290Y809400I0J-812D01*
G01Y808000D01*
G02X476936Y807330I-811J0D01*
G03Y806670I226J-330D01*
G02X477290Y806000I-457J-670D01*
G01Y804600D01*
G02X476478Y803788I-812J0D01*
G37*
G36*
G01X469978D02*
X468578D01*
G02X467766Y804600I0J812D01*
G01Y806000D01*
G02X468120Y806670I811J0D01*
G03Y807330I-226J330D01*
G02X467766Y808000I457J670D01*
G01Y809400D01*
G02X468578Y810212I812J0D01*
G01X469978D01*
G02X470790Y809400I0J-812D01*
G01Y808000D01*
G02X470436Y807330I-811J0D01*
G03Y806670I226J-330D01*
G02X470790Y806000I-457J-670D01*
G01Y804600D01*
G02X469978Y803788I-812J0D01*
G37*
G36*
G01X445478D02*
X444078D01*
G02X443266Y804600I0J812D01*
G01Y806000D01*
G02X443620Y806670I811J0D01*
G03Y807330I-226J330D01*
G02X443266Y808000I457J670D01*
G01Y809400D01*
G02X444078Y810212I812J0D01*
G01X445478D01*
G02X446290Y809400I0J-812D01*
G01Y808000D01*
G02X445936Y807330I-811J0D01*
G03Y806670I226J-330D01*
G02X446290Y806000I-457J-670D01*
G01Y804600D01*
G02X445478Y803788I-812J0D01*
G37*
G36*
G01X438978D02*
X437578D01*
G02X436766Y804600I0J812D01*
G01Y806000D01*
G02X437120Y806670I811J0D01*
G03Y807330I-226J330D01*
G02X436766Y808000I457J670D01*
G01Y809400D01*
G02X437578Y810212I812J0D01*
G01X438978D01*
G02X439790Y809400I0J-812D01*
G01Y808000D01*
G02X439436Y807330I-811J0D01*
G03Y806670I226J-330D01*
G02X439790Y806000I-457J-670D01*
G01Y804600D01*
G02X438978Y803788I-812J0D01*
G37*
G36*
G01X1370617Y609900D02*
X1369217D01*
G02X1368406Y610712I1J812D01*
G01Y612112D01*
G02X1369217Y612924I811J1D01*
G01X1370617D01*
G02X1371287Y612570I0J-811D01*
G03X1371947I330J226D01*
G02X1372617Y612924I670J-457D01*
G01X1374017D01*
G02X1374828Y612112I-1J-812D01*
G01Y610712D01*
G02X1374017Y609900I-811J-1D01*
G01X1372617D01*
G02X1371947Y610254I0J811D01*
G03X1371287I-330J-226D01*
G02X1370617Y609900I-670J457D01*
G37*
G36*
G01Y605400D02*
X1369217D01*
G02X1368406Y606212I1J812D01*
G01Y607612D01*
G02X1369217Y608424I811J1D01*
G01X1370617D01*
G02X1371287Y608070I0J-811D01*
G03X1371947I330J226D01*
G02X1372617Y608424I670J-457D01*
G01X1374017D01*
G02X1374828Y607612I-1J-812D01*
G01Y606212D01*
G02X1374017Y605400I-811J-1D01*
G01X1372617D01*
G02X1371947Y605754I0J811D01*
G03X1371287I-330J-226D01*
G02X1370617Y605400I-670J457D01*
G37*
G36*
G01Y600900D02*
X1369217D01*
G02X1368406Y601712I1J812D01*
G01Y603112D01*
G02X1369217Y603924I811J1D01*
G01X1370617D01*
G02X1371287Y603570I0J-811D01*
G03X1371947I330J226D01*
G02X1372617Y603924I670J-457D01*
G01X1374017D01*
G02X1374828Y603112I-1J-812D01*
G01Y601712D01*
G02X1374017Y600900I-811J-1D01*
G01X1372617D01*
G02X1371947Y601254I0J811D01*
G03X1371287I-330J-226D01*
G02X1370617Y600900I-670J457D01*
G37*
G36*
G01Y596400D02*
X1369217D01*
G02X1368406Y597212I1J812D01*
G01Y598612D01*
G02X1369217Y599424I811J1D01*
G01X1370617D01*
G02X1371287Y599070I0J-811D01*
G03X1371947I330J226D01*
G02X1372617Y599424I670J-457D01*
G01X1374017D01*
G02X1374828Y598612I-1J-812D01*
G01Y597212D01*
G02X1374017Y596400I-811J-1D01*
G01X1372617D01*
G02X1371947Y596754I0J811D01*
G03X1371287I-330J-226D01*
G02X1370617Y596400I-670J457D01*
G37*
G36*
G01Y588400D02*
X1369217D01*
G02X1368406Y589212I1J812D01*
G01Y590612D01*
G02X1369217Y591424I811J1D01*
G01X1370617D01*
G02X1371287Y591070I0J-811D01*
G03X1371947I330J226D01*
G02X1372617Y591424I670J-457D01*
G01X1374017D01*
G02X1374828Y590612I-1J-812D01*
G01Y589212D01*
G02X1374017Y588400I-811J-1D01*
G01X1372617D01*
G02X1371947Y588754I0J811D01*
G03X1371287I-330J-226D01*
G02X1370617Y588400I-670J457D01*
G37*
G36*
G01Y583900D02*
X1369217D01*
G02X1368406Y584712I1J812D01*
G01Y586112D01*
G02X1369217Y586924I811J1D01*
G01X1370617D01*
G02X1371287Y586570I0J-811D01*
G03X1371947I330J226D01*
G02X1372617Y586924I670J-457D01*
G01X1374017D01*
G02X1374828Y586112I-1J-812D01*
G01Y584712D01*
G02X1374017Y583900I-811J-1D01*
G01X1372617D01*
G02X1371947Y584254I0J811D01*
G03X1371287I-330J-226D01*
G02X1370617Y583900I-670J457D01*
G37*
G36*
G01X516400Y344988D02*
X515400D01*
G02X514788Y345600I0J612D01*
G01Y346400D01*
G02X515400Y347012I612J0D01*
G01X516400D01*
G02X516763Y346892I-1J-612D01*
G03X517237I237J322D01*
G02X517600Y347012I364J-492D01*
G01X518600D01*
G02X518805Y346976I-2J-612D01*
G03X519053Y347250I67J188D01*
G02X518996Y347385I1446J690D01*
G03X518757Y347509I-188J-69D01*
G02X518600Y347488I-159J591D01*
G01X517600D01*
G02X517237Y347608I1J612D01*
G03X516763I-237J-322D01*
G02X516400Y347488I-364J492D01*
G01X515400D01*
G02X514788Y348100I0J612D01*
G01Y348900D01*
G02X515400Y349512I612J0D01*
G01X516400D01*
G02X516763Y349392I-1J-612D01*
G03X517237I237J322D01*
G02X517600Y349512I364J-492D01*
G01X518600D01*
G02X518742Y349495I-1J-612D01*
G01X518765Y349489D01*
X518988D01*
Y350011D01*
X518765D01*
X518742Y350005D01*
G02X518600Y349988I-143J595D01*
G01X517600D01*
G02X517237Y350108I1J612D01*
G03X516763I-237J-322D01*
G02X516400Y349988I-364J492D01*
G01X515400D01*
G02X514788Y350600I0J612D01*
G01Y351400D01*
G02X515400Y352012I612J0D01*
G01X516400D01*
G02X516763Y351892I-1J-612D01*
G03X517237I237J322D01*
G02X517600Y352012I364J-492D01*
G01X518600D01*
G02X518774Y351986I-2J-612D01*
G03X519016Y352103I56J192D01*
G02X519088Y352256I1483J-605D01*
G03X518835Y352535I-176J94D01*
G02X518600Y352488I-235J564D01*
G01X517600D01*
G02X517237Y352608I1J612D01*
G03X516763I-237J-322D01*
G02X516400Y352488I-364J492D01*
G01X515400D01*
G02X514788Y353100I0J612D01*
G01Y353900D01*
G02X515400Y354512I612J0D01*
G01X516400D01*
G02X516763Y354392I-1J-612D01*
G03X517237I237J322D01*
G02X517600Y354512I364J-492D01*
G01X518600D01*
G02X519212Y353900I0J-612D01*
G01Y353100D01*
G02X519196Y352965I-612J4D01*
G03X519514Y352763I195J-44D01*
G02X522022Y350999I986J-1263D01*
G01X522012Y350968D01*
Y348469D01*
X522022Y348438D01*
G02X519526Y346665I-1522J-501D01*
G03X519206Y346480I-122J-159D01*
G02X519212Y346400I-606J-86D01*
G01Y345600D01*
G02X518600Y344988I-612J0D01*
G01X517600D01*
G02X517237Y345108I1J612D01*
G03X516763I-237J-322D01*
G02X516400Y344988I-364J492D01*
G37*
G36*
G01X488233Y320083D02*
G02X487071Y317098I-621J-1477D01*
G01X487040Y317109D01*
X484435Y317176D01*
X484403Y317166D01*
G02X483299Y319951I-448J1434D01*
G03X483309Y320666I-174J360D01*
G02X484502Y323416I691J1334D01*
G01X484532Y323405D01*
X486713Y323336D01*
X486743Y323344D01*
G02X488128Y320756I412J-1444D01*
G03X488233Y320083I260J-304D01*
G37*
G36*
G01X1245000Y270988D02*
X1243600D01*
G02X1242788Y271800I0J812D01*
G01Y273200D01*
G02X1243600Y274012I812J0D01*
G01X1245000D01*
G02X1245670Y273658I0J-811D01*
G03X1246330I330J226D01*
G02X1247000Y274012I670J-457D01*
G01X1248400D01*
G02X1249212Y273200I0J-812D01*
G01Y271800D01*
G02X1248400Y270988I-812J0D01*
G01X1247000D01*
G02X1246330Y271342I0J811D01*
G03X1245670I-330J-226D01*
G02X1245000Y270988I-670J457D01*
G37*
G36*
G01X1193168Y267048D02*
X1191768D01*
G02X1190956Y267860I0J812D01*
G01Y269260D01*
G02X1191768Y270072I812J0D01*
G01X1193168D01*
G02X1193838Y269718I0J-811D01*
G03X1194498I330J226D01*
G02X1195168Y270072I670J-457D01*
G01X1196568D01*
G02X1197380Y269260I0J-812D01*
G01Y267860D01*
G02X1196568Y267048I-812J0D01*
G01X1195168D01*
G02X1194498Y267402I0J811D01*
G03X1193838I-330J-226D01*
G02X1193168Y267048I-670J457D01*
G37*
G36*
G01X1245000Y266988D02*
X1243600D01*
G02X1242788Y267800I0J812D01*
G01Y269200D01*
G02X1243600Y270012I812J0D01*
G01X1245000D01*
G02X1245670Y269658I0J-811D01*
G03X1246330I330J226D01*
G02X1247000Y270012I670J-457D01*
G01X1248400D01*
G02X1249212Y269200I0J-812D01*
G01Y267800D01*
G02X1248400Y266988I-812J0D01*
G01X1247000D01*
G02X1246330Y267342I0J811D01*
G03X1245670I-330J-226D01*
G02X1245000Y266988I-670J457D01*
G37*
G36*
G01X1193168Y262548D02*
X1191768D01*
G02X1190956Y263360I0J812D01*
G01Y264760D01*
G02X1191768Y265572I812J0D01*
G01X1193168D01*
G02X1193838Y265218I0J-811D01*
G03X1194498I330J226D01*
G02X1195168Y265572I670J-457D01*
G01X1196568D01*
G02X1197380Y264760I0J-812D01*
G01Y263360D01*
G02X1196568Y262548I-812J0D01*
G01X1195168D01*
G02X1194498Y262902I0J811D01*
G03X1193838I-330J-226D01*
G02X1193168Y262548I-670J457D01*
G37*
G36*
G01X373190Y139908D02*
X373194Y142009D01*
X373184Y142040D01*
G02X375851Y143362I1423J480D01*
G03X376513I331J224D01*
G02X379178Y142034I1244J-842D01*
G01X379167Y142002D01*
X379163Y139911D01*
X379173Y139880D01*
G02X376509Y138554I-1423J-480D01*
G03X375846Y138552I-331J-225D01*
G02X373179Y139876I-1246J839D01*
G01X373190Y139908D01*
G37*
G36*
G01X385266Y138533D02*
G02X382603Y139871I-1247J838D01*
G01X382614Y139902D01*
X382638Y142022D01*
X382628Y142054D01*
G02X385300Y143362I1428J466D01*
G03X385962I331J224D01*
G02X388623Y142022I1244J-842D01*
G01X388612Y141991D01*
X388590Y139875D01*
X388600Y139844D01*
G02X385929Y138534I-1427J-468D01*
G03X385266Y138533I-331J-224D01*
G37*
G36*
G01X401542Y139885D02*
Y142006D01*
X401532Y142037D01*
G02X404197Y143363I1422J483D01*
G03X404860I331J224D01*
G02X407525Y142037I1243J-843D01*
G01X407514Y142005D01*
Y139886D01*
X407525Y139854D01*
G02X404859Y138529I-1422J-483D01*
G03X404197Y138528I-331J-225D01*
G02X401531Y139854I-1244J842D01*
G01X401542Y139885D01*
G37*
G36*
G01X394769Y138520D02*
G02X392087Y139821I-1259J819D01*
G01X392098Y139852D01*
X392094Y142003D01*
X392084Y142035D01*
G02X394749Y143362I1421J485D01*
G03X395411I331J224D01*
G02X398081Y142050I1243J-842D01*
G01X398071Y142018D01*
X398090Y139889D01*
X398101Y139858D01*
G02X395436Y138525I-1418J-496D01*
G03X394769Y138520I-332J-223D01*
G37*
G36*
G01X369741Y151443D02*
X369744Y149343D01*
X369755Y149312D01*
G02X369398Y147768I-1422J-485D01*
G03X369680Y147086I284J-282D01*
G01X370984Y147081D01*
X371016Y147091D01*
G02X371004Y144247I477J-1424D01*
G01X370973Y144258D01*
X369647Y144263D01*
G03X369366Y143577I-1J-400D01*
G02X369735Y142018I-1052J-1072D01*
G01X369724Y141986D01*
X369718Y139911D01*
X369729Y139880D01*
G02X369360Y138332I-1424J-479D01*
G03X369637Y137647I281J-285D01*
G01X370953Y137637D01*
X370984Y137647D01*
G02X370962Y134803I472J-1426D01*
G01X370930Y134814D01*
X368799Y134830D01*
X368768Y134820D01*
G02X367460Y137494I-472J1426D01*
G03X367462Y138158I-222J333D01*
G02X366884Y139888I843J1243D01*
G01X366895Y139920D01*
X366901Y141995D01*
X366890Y142026D01*
G02X367487Y143759I1424J479D01*
G03Y144426I-221J334D01*
G02X367478Y146928I827J1254D01*
G03X367482Y147589I-223J332D01*
G02X366910Y149308I851J1238D01*
G01X366921Y149340D01*
X366918Y151440D01*
X366907Y151471D01*
G02X367260Y153011I1422J485D01*
G03X366975Y153693I-284J282D01*
G01X365658Y153690D01*
X365626Y153679D01*
G02X365620Y156523I-486J1421D01*
G01X365651Y156513D01*
X366935Y156515D01*
G03X367215Y157200I-1J400D01*
G02X366857Y158776I1056J1068D01*
G01X366869Y158807D01*
X366905Y160911D01*
X366895Y160942D01*
G02X367276Y162474I1431J458D01*
G03X366993Y163160I-279J286D01*
G01X365686Y163148D01*
X365655Y163137D01*
G02X365627Y165981I-497J1417D01*
G01X365659Y165971D01*
X366971Y165983D01*
G03X367255Y166661I-4J400D01*
G02X366908Y168178I1079J1045D01*
G01X366918Y168209D01*
X366902Y170304D01*
X366891Y170336D01*
G02X369735Y170358I1418J494D01*
G01X369725Y170327D01*
X369741Y168232D01*
X369752Y168201D01*
G02X369189Y166471I-1418J-495D01*
G03X369187Y165815I228J-329D01*
G02X369147Y163328I-862J-1230D01*
G03Y162658I218J-335D01*
G02X369740Y160892I-821J-1258D01*
G01X369728Y160861D01*
X369692Y158757D01*
X369702Y158726D01*
G02X369131Y157036I-1431J-458D01*
G03X369144Y156372I229J-328D01*
G02X369173Y153862I-811J-1265D01*
G03X369172Y153199I223J-332D01*
G02X369752Y151475I-843J-1243D01*
G01X369741Y151443D01*
G37*
G36*
G01X1095572Y96030D02*
X1088350D01*
Y100454D01*
X1088435D01*
X1088454Y100631D01*
G02X1088803Y101212I807J-89D01*
G03Y101872I-226J330D01*
G02X1088454Y102453I458J670D01*
G01X1088435Y102630D01*
X1088350D01*
Y107054D01*
X1095572D01*
Y102630D01*
X1095487D01*
X1095468Y102453D01*
G02X1095119Y101872I-807J89D01*
G03Y101212I226J-330D01*
G02X1095468Y100631I-458J-670D01*
G01X1095487Y100454D01*
X1095572D01*
Y96030D01*
G37*
G54D64*
X1272441Y7087D03*
X1299213D03*
G54D62*
X1224016Y180709D03*
G54D60*
X945197Y380000D03*
X968819D03*
G54D65*
X1379862Y108465D03*
Y119095D03*
G54D63*
X1224016Y386221D03*
G54D55*
X35435Y373228D03*
X82675D03*
G54D54*
X21220D03*
X96890D03*
X157480Y283071D03*
X220472D03*
G54D67*
X402953Y23622D03*
X413189D03*
X423425D03*
G54D50*
X1227165Y411417D03*
X1227166Y155511D03*
X1008268Y411417D03*
G54D51*
Y244094D03*
G54D56*
X270078Y92125D03*
Y155117D03*
X490944Y79921D03*
Y255118D03*
X743897Y353543D03*
Y410629D03*
X1305117Y87548D03*
Y262745D03*
X1376968Y147243D03*
Y216535D03*
G54D59*
X600925Y44134D03*
X638917D03*
G54D58*
X537994Y303150D03*
X825984D03*
G54D57*
X332086Y408858D03*
X355708Y96456D03*
X450196Y257874D03*
X572243Y337992D03*
G54D52*
X211811Y313347D03*
X208661D03*
X203937Y303465D03*
X200787D03*
X213385D03*
X177165Y313347D03*
X174015D03*
X169291Y303465D03*
X164567Y313347D03*
X166141Y303465D03*
X74015Y403503D03*
X70865D03*
X64565D03*
X61415D03*
G54D69*
X1094250Y90300D03*
Y79700D03*
G54D66*
X373894Y7992D03*
X386264D03*
G54D53*
X202362Y313347D03*
X210236Y303465D03*
X199212Y313347D03*
X167716D03*
X178740Y303465D03*
X175590D03*
X55120Y403503D03*
X51970D03*
X45670D03*
X42520D03*
G54D61*
X1215250Y264550D03*
Y277250D03*
Y289750D03*
Y302350D03*
Y314950D03*
X1232750Y270850D03*
Y283450D03*
Y296050D03*
Y308650D03*
Y321250D03*
G54D68*
X421942Y7992D03*
X432704D03*
G54D17*
X50000Y659500D03*
X58804Y699720D03*
X109000Y844220D03*
X111000Y981500D03*
X124500Y515500D03*
X128000Y544050D03*
X121200Y584278D03*
X166200Y506500D03*
X172000Y486400D03*
X182000Y577500D03*
X176938Y680465D03*
X182500Y677500D03*
X234000Y562000D03*
X236500Y574000D03*
X238500Y705000D03*
X253500Y707250D03*
X294500Y98500D03*
X313402Y156000D03*
X306155Y497700D03*
X331040Y152601D03*
X330929Y148600D03*
X317248Y156000D03*
X320338Y507683D03*
X347000Y120040D03*
X340000D03*
X344055Y529000D03*
X340055Y524000D03*
X342971Y525750D03*
X339000Y878500D03*
X336000Y871500D03*
X339000Y894000D03*
Y885500D03*
X337300Y949500D03*
X353740Y133300D03*
X352040Y143000D03*
X349829Y153400D03*
X355084Y172441D03*
X351929Y162200D03*
X362036Y177155D03*
X358858Y177128D03*
X358848Y174010D03*
X358879Y192929D03*
X351320Y194520D03*
X361987Y189747D03*
X358850Y196050D03*
X355090Y195660D03*
X355139Y190099D03*
X351731Y190274D03*
X362500Y286000D03*
X361155Y496203D03*
X356555Y513000D03*
X357055Y507000D03*
X356055Y502000D03*
X368296Y136246D03*
X371456Y136221D03*
X368305Y139401D03*
X371482Y133058D03*
X365133Y129133D03*
X374600Y139390D03*
X377750Y139400D03*
X368333Y155107D03*
X365140Y155100D03*
X377757Y145670D03*
X368333Y148827D03*
X368329Y151956D03*
X371493Y145667D03*
X368314Y142505D03*
Y145680D03*
X371457Y155080D03*
X377759Y152000D03*
X365146Y151942D03*
X365182Y142532D03*
X374607Y142520D03*
X377757D03*
X368309Y170830D03*
X368334Y167706D03*
X365158Y164554D03*
X368325Y164585D03*
X368326Y161400D03*
X368271Y158268D03*
X374582Y161404D03*
X374577Y164559D03*
X377750Y170846D03*
X374570Y158267D03*
X365176Y161400D03*
X365187Y186605D03*
X368308Y177202D03*
X374560Y177210D03*
X371485Y177175D03*
X368307Y205511D03*
Y199211D03*
X368336Y192904D03*
X374606Y189763D03*
Y192912D03*
X377756Y211810D03*
X365158D03*
X371457D03*
X367665Y363430D03*
X368055Y380500D03*
X368555Y385000D03*
Y376500D03*
Y389000D03*
X368165Y393402D03*
X370500Y518000D03*
X379500Y963500D03*
X390355Y139371D03*
X380920Y139370D03*
X387173Y139376D03*
X392240Y129000D03*
X383680Y129030D03*
X396683Y139362D03*
X393510Y139340D03*
X384019Y139371D03*
X384056Y145670D03*
X390355D03*
X396655D03*
X387206Y142520D03*
X384056D03*
X390339Y151990D03*
X396639D03*
X380888Y148799D03*
X396655Y142520D03*
X393505D03*
X387205Y167715D03*
X384041Y170888D03*
X380928Y167701D03*
X393528Y167702D03*
X384030Y177120D03*
X393542Y186614D03*
X393490Y174039D03*
X393541Y180315D03*
X384036Y189747D03*
X393519Y192900D03*
X387209Y192930D03*
X384055Y211810D03*
X393504Y218109D03*
X395500Y237000D03*
X389500Y319150D03*
X392589Y317729D03*
X394055Y335000D03*
X391325Y324520D03*
X386755Y326100D03*
X384160Y328812D03*
X391555Y338350D03*
X393061Y346800D03*
X393755Y350500D03*
X390230Y349327D03*
X396055Y338000D03*
X395855Y366890D03*
X392991Y365797D03*
X391628Y358852D03*
X394915Y359725D03*
X387515Y365500D03*
X387265Y384370D03*
X394935Y385150D03*
X382803Y385207D03*
X391215Y384900D03*
X396490Y388597D03*
X388500Y400575D03*
X390543Y391950D03*
X387000Y404275D03*
X388750Y951750D03*
X387061Y986061D03*
X389500Y992000D03*
X399783Y136237D03*
X402953Y139370D03*
X402800Y129180D03*
X406103Y139371D03*
X406110Y145660D03*
X402954Y145670D03*
Y142520D03*
X406103D03*
X402938Y151950D03*
X399827Y167702D03*
X406140Y167716D03*
X406127Y161404D03*
X412427D03*
X412426Y167703D03*
X399841Y186614D03*
X399840Y180315D03*
X399790Y174039D03*
X406126Y174003D03*
X406139Y180315D03*
X406101Y186613D03*
X412426Y174003D03*
X412439Y186614D03*
X412400Y180314D03*
X406128Y192901D03*
X399791Y192938D03*
X412428Y192901D03*
X399803Y211810D03*
X406102D03*
X406099Y214950D03*
X409249Y214965D03*
X412767Y233162D03*
X400000Y237500D03*
X409500Y271500D03*
X404920Y334054D03*
X412794D03*
X408857D03*
X400983D03*
X397983Y333998D03*
X408857Y330117D03*
X400523Y325283D03*
X412794Y341928D03*
X397555Y345146D03*
X398055Y350296D03*
X398555Y339283D03*
X408857Y345865D03*
X404965Y342120D03*
X412794Y337991D03*
X400055Y343146D03*
X412794Y365550D03*
Y357676D03*
X397117Y364138D03*
X412794Y353739D03*
X404920Y369487D03*
X412794Y361613D03*
X408925Y361680D03*
X400395Y362450D03*
X400885Y354120D03*
X404935Y353840D03*
X412794Y369487D03*
X408857D03*
Y353739D03*
X412794Y377363D03*
Y385237D03*
Y381300D03*
X399923Y372000D03*
X412794Y400985D03*
Y393111D03*
X408857Y389174D03*
X400983Y400985D03*
X404920Y397048D03*
Y400985D03*
Y389174D03*
X412794Y397048D03*
Y389174D03*
X408857Y397048D03*
X400983D03*
X404920Y393111D03*
X412794Y416733D03*
Y408859D03*
X400983Y404922D03*
X412794Y412796D03*
X404920Y404922D03*
X408857D03*
Y412796D03*
X412794Y404922D03*
X404920Y416733D03*
X400983D03*
X412794Y424607D03*
X408857Y420670D03*
X412794D03*
X404555Y430500D03*
X404920Y420670D03*
X406555Y428300D03*
X399555Y438500D03*
X428375Y119735D03*
X418940Y125000D03*
X415552Y136221D03*
X421590Y128500D03*
X418702Y136221D03*
X413540Y128500D03*
X425000Y136220D03*
X428116Y136218D03*
X421851Y136221D03*
X423686Y126215D03*
X421851Y142520D03*
X415552D03*
X428151D03*
X418700Y148818D03*
X428149D03*
X415551D03*
X424999D03*
X421850D03*
X428149Y161416D03*
X418726Y167703D03*
Y174003D03*
Y180303D03*
X418701Y186614D03*
X424999Y192912D03*
X418727Y192902D03*
X428150Y211810D03*
X415551D03*
X421850D03*
X428172Y221320D03*
X424979Y218127D03*
X428047Y218049D03*
X415551Y218109D03*
X418729Y218100D03*
X421850Y218109D03*
X418729Y221268D03*
X420500Y234500D03*
X422630Y227232D03*
X426147Y230982D03*
X420714Y225190D03*
X429444Y230192D03*
X419000Y227405D03*
X427965Y318293D03*
X419913Y318051D03*
X417650Y316400D03*
X416482Y319022D03*
X424555Y318000D03*
X420668Y334054D03*
X428542D03*
X424023Y320783D03*
X424605Y334054D03*
Y330117D03*
X416731D03*
X416950Y321783D03*
X416731Y334054D03*
X420668Y337991D03*
X428542Y345865D03*
X416615Y349930D03*
X428542Y349802D03*
Y341928D03*
X424605Y337991D03*
X428542D03*
X420668Y341928D03*
X424605Y349802D03*
X420668D03*
X416731Y337991D03*
X420668Y345865D03*
X416731Y341928D03*
X424605D03*
X428542Y361613D03*
Y369487D03*
Y353739D03*
X416731D03*
X420668Y357676D03*
X428542Y365550D03*
X416731Y369487D03*
X420668Y353739D03*
X416731Y365550D03*
X424605D03*
X420668D03*
X416731Y361613D03*
X420668Y369487D03*
X424605Y357676D03*
X420668Y361613D03*
X416555Y357500D03*
X428542Y357676D03*
Y385237D03*
Y381300D03*
X428500Y377000D03*
X416731Y381300D03*
Y377363D03*
X428445Y373550D03*
X420668Y377363D03*
Y385237D03*
X416731D03*
X424605Y381300D03*
X420668D03*
X416731Y389174D03*
X428555Y393000D03*
X420668Y389174D03*
X416731Y393111D03*
Y397048D03*
X420668Y393111D03*
X424605Y397048D03*
X428542Y389174D03*
X420668Y397048D03*
X416731Y400985D03*
X424605Y389174D03*
Y404922D03*
Y408859D03*
X420668Y404922D03*
X428542Y408859D03*
X420668D03*
X428542Y404922D03*
X416731Y412796D03*
X424605D03*
X432540Y123000D03*
X435640D03*
X437599Y136221D03*
X434450D03*
X439540Y124500D03*
X431407Y136285D03*
X440931Y129061D03*
X431348Y125911D03*
X442323Y126000D03*
X437945Y127159D03*
X437598Y148818D03*
Y155118D03*
X434450Y142520D03*
X440765Y145670D03*
X443928Y148811D03*
X443891Y151999D03*
X443890Y142565D03*
X443909Y145650D03*
X443936Y155118D03*
X437598Y167716D03*
Y161417D03*
X443899Y161430D03*
X443882Y167737D03*
X443899Y164530D03*
X443871Y158278D03*
X437598Y174015D03*
Y180314D03*
Y186614D03*
X443910Y174041D03*
X443879Y180320D03*
X443887Y177138D03*
X440769Y183480D03*
X443919D03*
X437598Y205511D03*
Y199212D03*
Y192913D03*
X443897Y205512D03*
Y192914D03*
X443898Y199212D03*
X443897Y202363D03*
Y196063D03*
X437598Y211810D03*
X443897Y211811D03*
Y208662D03*
X431336Y218111D03*
X434448Y218109D03*
X437598D03*
X436529Y229500D03*
X434334Y226789D03*
X443113Y226339D03*
X439980Y232126D03*
X441379Y229700D03*
X432307Y224857D03*
X437112Y232239D03*
X445892Y225995D03*
X438500Y250000D03*
X431023Y317283D03*
X440353Y330117D03*
X434448Y320783D03*
X440353Y334054D03*
X432523Y330283D03*
X444555Y334000D03*
X441335Y321000D03*
X436416Y334054D03*
X432585Y345850D03*
X444290Y341928D03*
X432365Y341880D03*
X444290Y337991D03*
X432605Y337880D03*
X444290Y345865D03*
X440353D03*
X440555Y338000D03*
X444290Y369487D03*
X436416D03*
X440353Y357676D03*
X444290Y353739D03*
X440353Y365550D03*
X436416Y353739D03*
Y361613D03*
X432479Y381300D03*
X444290D03*
X440353Y377363D03*
X436416Y381300D03*
X444290Y397048D03*
X440353D03*
X436416D03*
X444290Y400985D03*
X436416D03*
X444290Y389174D03*
X436416D03*
X432479Y408859D03*
Y404922D03*
X436416D03*
Y408859D03*
X444290Y404922D03*
Y408859D03*
X440353D03*
Y404922D03*
Y412796D03*
X432479D03*
X448669Y126510D03*
X450209Y129230D03*
X447389Y129580D03*
X454676Y137495D03*
X456429Y135000D03*
X457929Y132500D03*
X451679Y148250D03*
X461685Y150386D03*
X455731Y154302D03*
X460300Y141100D03*
X454929Y146500D03*
X453929Y140334D03*
X459069Y151980D03*
X451329Y165570D03*
X453599Y156693D03*
X450196Y189764D03*
X454329Y199800D03*
X452929Y203900D03*
X452329Y194300D03*
X447063Y199234D03*
X447047Y189764D03*
X451292Y197637D03*
X456479Y202400D03*
X455929Y192800D03*
X456229Y196700D03*
X453829Y215600D03*
X453729Y219300D03*
X452393Y210236D03*
X458029Y213469D03*
X457798Y217769D03*
X457729Y206800D03*
X448840Y225775D03*
X455429Y227500D03*
X451929Y229800D03*
X456929Y224507D03*
X460040Y330117D03*
X448227D03*
X452223Y333983D03*
X448227Y334054D03*
X460040D03*
X456103D03*
Y341928D03*
X460040Y337991D03*
X455825Y349840D03*
X448000Y346000D03*
X456055Y338000D03*
X452055D03*
X452165Y349470D03*
X456103Y369487D03*
Y353739D03*
Y361613D03*
X460040Y357676D03*
Y365550D03*
X448227D03*
Y357676D03*
X460040Y385237D03*
X456103Y381300D03*
X460040Y377363D03*
X448227Y385237D03*
Y377363D03*
X456103Y397048D03*
X448227D03*
X456103Y389174D03*
X456223Y404883D03*
Y408783D03*
X452123Y416783D03*
X460040Y412796D03*
X448227D03*
X452223Y404883D03*
X448227Y408859D03*
X452223Y408783D03*
X448227Y404922D03*
X471480Y105660D03*
X466464Y151000D03*
X466500Y144500D03*
X463969Y147610D03*
X469429Y172500D03*
Y165590D03*
X473131Y169131D03*
X477429Y162500D03*
X469429Y179500D03*
X464570Y215750D03*
X467300Y320100D03*
X467914Y330117D03*
X463977Y334054D03*
X467914D03*
X475788Y330117D03*
X463977Y341928D03*
X471851Y337991D03*
X467914D03*
X463977D03*
X471851Y349802D03*
X467914Y345865D03*
X471851Y361613D03*
Y369487D03*
Y353739D03*
Y357676D03*
X463977Y369487D03*
Y361613D03*
X471851Y377363D03*
Y381300D03*
X463977D03*
Y400985D03*
X471851D03*
Y389174D03*
X463977D03*
Y408859D03*
Y404922D03*
X467914Y408859D03*
Y404922D03*
X475788Y412796D03*
X471851Y416733D03*
X467914Y412796D03*
X480500Y181800D03*
X483955Y318600D03*
X487500Y333833D03*
X483662Y334054D03*
X487599Y330117D03*
X483662Y326180D03*
X484000Y322000D03*
X487599Y326180D03*
X487155Y321900D03*
X483662Y330117D03*
X487599Y337991D03*
X483662D03*
Y341928D03*
X487599D03*
X483662Y345865D03*
X487599Y349802D03*
X483662D03*
X487599Y345865D03*
X479725Y341928D03*
Y349802D03*
X487603Y369483D03*
X483662Y357676D03*
X487599D03*
X483663Y365463D03*
X483662Y361613D03*
Y353739D03*
X487599D03*
X483683Y369403D03*
X491536Y369487D03*
Y361613D03*
X479725Y365550D03*
Y357676D03*
X491536Y381300D03*
X479725Y385237D03*
Y377363D03*
X491536Y397048D03*
Y389174D03*
X479725Y400985D03*
Y393111D03*
X491536Y412796D03*
Y404922D03*
X483662Y412796D03*
Y404922D03*
X479725Y416733D03*
X487599Y420670D03*
X495473Y334054D03*
Y341928D03*
Y385237D03*
Y377363D03*
Y400985D03*
Y393111D03*
X521700Y114000D03*
X533441Y211775D03*
X559750Y264500D03*
X605000Y209500D03*
X604500Y227500D03*
Y223000D03*
X599000Y804000D03*
X622500Y696500D03*
X625000Y706000D03*
X632500Y530000D03*
X691400Y231100D03*
X710100Y182700D03*
X780000Y250000D03*
X862500Y65000D03*
X865000Y488500D03*
X874000Y56000D03*
X873500Y61500D03*
X884500Y323500D03*
X881000Y736500D03*
X945000Y141500D03*
X947500Y153000D03*
X959900Y180700D03*
X974500Y188500D03*
X975007Y194300D03*
X1002500Y653000D03*
X1001100Y776500D03*
X1015000Y477500D03*
X1011500Y667500D03*
X1022000Y492500D03*
X1022500Y637500D03*
X1027504Y853366D03*
X1045000Y266600D03*
X1041410Y695394D03*
Y690694D03*
Y699834D03*
X1055000Y214500D03*
X1055500Y360000D03*
X1062940Y629945D03*
X1065978Y664568D03*
X1063056Y681554D03*
X1062700Y672600D03*
X1054080Y680630D03*
X1084500Y223500D03*
X1074000Y660500D03*
X1074500Y665500D03*
X1088000Y461000D03*
X1103300Y492000D03*
X1114500Y645000D03*
X1118630Y714820D03*
X1116550Y783600D03*
X1119060Y791083D03*
X1132500Y333000D03*
X1126500Y614500D03*
X1132423Y663902D03*
X1135553Y663957D03*
X1132440Y676555D03*
X1129272Y673350D03*
X1129271Y670275D03*
X1126102Y676518D03*
X1132402Y673405D03*
X1132398Y667102D03*
X1129290Y676555D03*
X1126121Y679722D03*
X1132421Y679648D03*
X1132395Y670225D03*
X1126117Y685952D03*
X1129273Y689170D03*
X1126122Y689171D03*
X1129290Y692303D03*
X1126116Y692279D03*
X1132423Y695469D03*
X1132440Y692265D03*
Y686004D03*
X1132434Y682860D03*
X1129278Y682804D03*
X1129289Y686005D03*
X1126157Y695435D03*
X1129238Y704878D03*
X1132440Y701714D03*
X1129270D03*
X1126121Y711218D03*
X1129285Y708056D03*
X1126114Y701703D03*
X1126093Y704874D03*
X1132406Y704904D03*
X1132440Y698564D03*
X1129290D03*
X1126155Y708029D03*
X1132445Y714345D03*
X1129260Y714350D03*
X1126121Y714368D03*
X1132417Y711189D03*
X1129277Y711210D03*
X1128959Y729952D03*
X1126969Y727981D03*
X1132459Y717481D03*
X1127183Y740805D03*
X1126671Y744629D03*
X1126885Y736721D03*
X1123393Y743726D03*
X1124497Y734140D03*
X1124326Y738960D03*
X1126955Y731909D03*
X1124978Y747578D03*
X1130900Y766700D03*
X1124460Y768140D03*
X1125900Y764200D03*
X1129501Y776929D03*
X1120400Y781600D03*
X1126360Y792640D03*
X1127160Y788837D03*
X1129497Y792673D03*
X1130610Y788820D03*
X1134145Y788450D03*
X1132684Y792636D03*
X1124360Y788390D03*
X1132600Y784822D03*
X1120529Y786350D03*
X1123254Y792663D03*
X1131095Y799965D03*
X1124796Y800150D03*
X1144425Y325500D03*
X1143000Y629000D03*
X1138757Y663937D03*
X1151354Y663936D03*
X1148150Y663956D03*
X1141900Y663944D03*
X1148188Y667106D03*
Y670256D03*
X1151282Y667088D03*
X1141600Y673590D03*
X1141954Y676581D03*
X1135589Y673368D03*
X1144983Y667085D03*
X1145020Y670200D03*
X1136150Y676500D03*
X1135685Y679613D03*
X1135598Y667080D03*
X1135595Y670225D03*
X1141868Y670273D03*
X1138708Y667113D03*
X1139245Y675106D03*
X1135589Y682854D03*
Y695415D03*
X1139858Y692074D03*
X1139000Y685667D03*
X1144880Y707720D03*
X1145000Y711200D03*
X1138729Y714360D03*
X1151307Y714306D03*
X1141765Y711030D03*
X1145053Y714327D03*
X1148169Y711219D03*
X1141840Y714339D03*
X1138320Y710066D03*
X1135589Y701714D03*
X1151352Y711178D03*
X1140710Y707750D03*
X1138400Y705300D03*
X1136304Y707482D03*
X1151318Y717518D03*
X1148135Y720634D03*
X1138685Y720633D03*
X1141870Y717518D03*
X1148167Y717517D03*
X1138730Y717480D03*
X1141904Y720633D03*
X1150734Y736950D03*
X1149470Y734451D03*
X1137030Y745300D03*
X1146370Y769310D03*
X1142095Y773774D03*
X1151564Y776924D03*
X1146200Y766300D03*
X1142323Y780250D03*
X1138961Y776940D03*
X1150310Y783840D03*
X1142120Y795830D03*
X1145270D03*
X1138970D03*
X1145270Y792670D03*
X1141700Y785113D03*
X1138545Y787952D03*
X1145740Y789140D03*
X1138931Y792658D03*
X1142086Y789513D03*
X1136236Y782142D03*
X1151590Y792660D03*
X1143470Y782805D03*
X1141100Y831600D03*
X1157599Y663956D03*
X1167098Y663932D03*
X1160748Y660807D03*
Y657657D03*
X1160741Y663949D03*
X1163946Y663946D03*
X1157613Y673418D03*
X1167692Y674996D03*
X1160768Y676535D03*
X1154470Y673363D03*
X1152090Y677010D03*
X1163917Y670275D03*
X1160741Y667099D03*
X1163914Y673352D03*
X1167034Y667092D03*
X1157655Y667087D03*
X1160770Y673421D03*
X1163944Y667076D03*
X1154487Y670256D03*
X1157670Y707960D03*
X1167048Y714312D03*
X1163968Y708000D03*
X1154434Y714335D03*
X1157581Y714331D03*
X1163905Y711206D03*
X1157636Y711200D03*
X1167103Y711107D03*
X1167000Y727500D03*
X1157637Y717463D03*
X1157643Y720642D03*
X1152248Y730404D03*
X1154430Y717481D03*
X1152400Y727600D03*
X1167049Y717501D03*
X1167048Y720612D03*
X1163898Y717462D03*
Y720612D03*
X1157112Y731702D03*
X1164200Y744500D03*
X1157000Y734500D03*
X1163830Y747899D03*
X1158100Y769700D03*
X1162450Y769190D03*
X1167002Y767508D03*
X1167326Y776936D03*
X1161051Y792660D03*
X1164196Y795814D03*
X1153219Y781303D03*
X1161545Y788844D03*
X1162693Y780865D03*
X1158092Y787715D03*
X1154712Y792690D03*
X1165492Y780957D03*
X1154200Y788900D03*
X1154700Y795790D03*
X1161022Y785693D03*
X1165063Y787500D03*
X1167410Y785530D03*
X1154800Y799000D03*
X1173332Y663938D03*
X1176506Y663916D03*
X1176525Y679676D03*
X1170181Y670240D03*
X1176503Y670218D03*
X1182803Y670234D03*
X1176534Y673368D03*
X1179653Y670234D03*
X1173309Y673406D03*
X1179662Y673421D03*
X1176534Y676555D03*
X1179667Y679655D03*
X1182831Y679666D03*
X1182815Y676573D03*
X1170192Y667100D03*
X1176526Y667092D03*
X1173403Y670237D03*
X1173349Y667099D03*
X1182785Y685977D03*
X1176520Y685970D03*
X1179663Y685959D03*
X1173365Y695397D03*
X1169800Y682200D03*
X1173392Y685974D03*
X1173389Y689121D03*
X1176482Y682840D03*
X1176529Y692276D03*
X1179685Y692292D03*
X1176496Y695415D03*
X1179664Y695466D03*
X1182796Y695415D03*
X1179678Y689111D03*
X1182817Y689155D03*
X1173384Y692265D03*
X1182815Y701696D03*
X1182796Y708013D03*
X1182813Y698619D03*
X1170248Y714330D03*
X1173350Y698590D03*
X1179703Y714331D03*
X1173347Y714350D03*
X1176503Y714342D03*
X1176515Y704845D03*
X1179676Y711207D03*
X1179660Y704850D03*
X1171200Y706170D03*
X1179660Y708050D03*
X1176515Y708045D03*
X1173015Y708329D03*
X1176515Y711144D03*
X1173262Y711119D03*
X1182802Y714356D03*
X1169282Y729708D03*
X1173400Y717480D03*
X1176499Y720609D03*
X1170199Y717501D03*
X1173348Y720613D03*
X1176489Y717469D03*
X1171500Y733725D03*
X1175000Y734870D03*
X1171108Y777368D03*
X1170950Y795960D03*
X1170911Y784912D03*
X1170718Y782118D03*
X1185965Y676573D03*
X1190500Y674207D03*
X1190000Y699500D03*
Y705500D03*
X1199500Y743500D03*
X1201250Y627000D03*
X1218040Y719850D03*
X1249773Y551500D03*
X1279600Y694800D03*
X1287962Y710490D03*
X1289500Y716500D03*
X1292500Y730478D03*
X1305000Y596500D03*
X1306423Y608164D03*
X1306443Y618985D03*
X1307150Y691500D03*
X1307000Y729100D03*
X1310500Y737500D03*
X1307000Y732500D03*
X1300491Y732991D03*
X1322900Y524600D03*
X1322400Y533100D03*
X1318000Y696500D03*
X1319000Y708000D03*
X1351900Y524600D03*
X1352400Y533600D03*
X1381415Y581195D03*
X1380925Y598315D03*
X1377996Y610847D03*
X1380925Y602035D03*
X1377996Y607382D03*
X1385135Y581195D03*
G54D13*
X8200Y857700D03*
X8000Y853500D03*
X35304Y832220D03*
X34304Y897720D03*
X47483Y387776D03*
X43883Y387769D03*
X52000Y655500D03*
X44804Y837220D03*
X44500Y851500D03*
X49000Y861500D03*
X52000Y872720D03*
X37232Y877242D03*
X51896Y878668D03*
X42554Y891720D03*
X37211Y881115D03*
X37758Y884674D03*
X40304Y887220D03*
X51304Y882220D03*
X47804Y906720D03*
X43804Y907720D03*
X41304Y927220D03*
X50270Y929186D03*
X62783Y387776D03*
X66483Y387876D03*
X56883D03*
X53183Y387676D03*
X55304Y669720D03*
X58804Y710220D03*
X68147Y722511D03*
X62704Y739620D03*
X55304Y746220D03*
X65272Y758504D03*
X64683Y762056D03*
X59272Y790504D03*
X57772Y801504D03*
X61492Y803004D03*
X55022Y826720D03*
X66022Y827254D03*
X57304Y815720D03*
X61304Y815220D03*
X65804Y835720D03*
X57804Y834720D03*
X61804D03*
X52304Y868220D03*
X60804Y907720D03*
X56804Y907220D03*
X52304Y906720D03*
X64804Y907720D03*
X52804Y943220D03*
X57770Y932686D03*
X55270Y929186D03*
X52770Y932686D03*
X62770D03*
X60270Y929186D03*
X52804Y938795D03*
X71883Y387976D03*
X76083D03*
X76804Y710220D03*
X71846Y722426D03*
X77272Y724004D03*
X75432Y735059D03*
X83849Y735513D03*
X80272Y735103D03*
X68910Y760642D03*
X83112Y760720D03*
X75432Y758844D03*
X80624Y764241D03*
X68762Y764239D03*
X82804Y794920D03*
X84804Y808720D03*
X79000Y836500D03*
X84221Y836078D03*
X77500Y832000D03*
X70909Y847325D03*
X72304Y869720D03*
X76304D03*
X81304Y884470D03*
X89804Y669720D03*
X95304Y686220D03*
X94804Y708220D03*
X99804Y709220D03*
X87772Y735059D03*
X92365Y735040D03*
X85672Y763504D03*
X86404Y774720D03*
X85304Y768720D03*
X93347Y765754D03*
X85204Y798220D03*
X92304Y835720D03*
X87928Y848107D03*
X95700Y926300D03*
X105000Y834500D03*
X113222Y831222D03*
X112500Y835000D03*
X110500Y848500D03*
X115500D03*
X109054Y892720D03*
X102304Y895220D03*
X114054Y892720D03*
X106554Y895720D03*
X116554D03*
X111554Y896220D03*
X105804Y943220D03*
X109054Y932720D03*
X116600Y929924D03*
X114054Y932470D03*
X111554Y929720D03*
X108804Y938795D03*
X115500Y983500D03*
X127654Y293453D03*
X132123Y318877D03*
X123654Y320953D03*
X131500Y324000D03*
X122906Y331953D03*
X127301Y354709D03*
X131147D03*
X132500Y547000D03*
Y559600D03*
Y556000D03*
Y551500D03*
X133500Y582500D03*
X125050Y583000D03*
X126500Y587500D03*
X121685Y587919D03*
X134000Y587000D03*
X130000Y666500D03*
X129304Y798720D03*
X122500Y845500D03*
X128000Y870500D03*
X129100Y892924D03*
X124054Y892220D03*
X121600Y895266D03*
X119054Y892720D03*
X126554Y895470D03*
X121598Y929924D03*
X131554Y929470D03*
X129054Y932720D03*
X126554Y929882D03*
X124098Y932515D03*
X119099Y932516D03*
X118000Y991500D03*
X145500Y283500D03*
X143147Y354709D03*
X139301D03*
X147500Y472100D03*
X135500Y511000D03*
X136000Y566000D03*
X136500Y576900D03*
Y573300D03*
Y580500D03*
Y569700D03*
X140500Y568000D03*
X144000Y572500D03*
X143500Y710500D03*
X141054Y795820D03*
X150225Y790412D03*
X146304Y804220D03*
X146500Y808220D03*
X165793Y294309D03*
X155874Y313961D03*
Y317807D03*
X164147Y328699D03*
X155874Y326957D03*
Y323111D03*
X155147Y354709D03*
X162801D03*
X166647D03*
X151301D03*
X160000Y465500D03*
X153050Y486500D03*
X154625Y550290D03*
X163305Y554750D03*
X160500Y586500D03*
X156900D03*
X152948Y587000D03*
X166000Y662500D03*
X157750Y662250D03*
X166500Y650500D03*
X162500Y670000D03*
X163000Y710500D03*
X150900Y812500D03*
X154500D03*
X152500Y840000D03*
X157500Y867500D03*
X169639Y294309D03*
X179088Y294909D03*
X175242D03*
X167993Y328699D03*
X179622Y328749D03*
X175776D03*
X182800Y471300D03*
X171500Y478699D03*
X177493Y533493D03*
X175993Y559938D03*
X167469Y588969D03*
X174000Y830500D03*
X170500Y835500D03*
X179500Y847000D03*
X172000Y868000D03*
X168400D03*
X183000Y865750D03*
X188295Y297209D03*
X193841Y297755D03*
X185039Y295209D03*
X191295D03*
X186614Y319028D03*
X190295Y318709D03*
X198864Y323297D03*
X192874Y334307D03*
Y330461D03*
X184295Y322209D03*
X192795Y321709D03*
X192874Y341611D03*
Y345457D03*
X187300Y457300D03*
X191800D03*
X185000Y533562D03*
X185305Y521100D03*
X195865Y552940D03*
X198500Y563000D03*
X189500Y573500D03*
X194500Y724000D03*
X186000Y841500D03*
X185000Y856000D03*
X185500Y848260D03*
X187000Y878000D03*
X199000Y891500D03*
X190500Y894000D03*
X195000Y891500D03*
X204285Y294909D03*
X213733D03*
X200439D03*
X209887D03*
X208338Y323297D03*
X202710D03*
X212134D03*
X204500Y470000D03*
X207773Y516562D03*
X208305Y548670D03*
Y536320D03*
X203000Y564500D03*
X212500Y716500D03*
X204500Y721000D03*
X215250Y833750D03*
X205500Y830000D03*
X204000Y862000D03*
X212000Y891500D03*
X203500Y894000D03*
X208000Y892000D03*
X232500Y425000D03*
X229055Y497000D03*
X216500Y516000D03*
X228319Y524798D03*
X230000Y680500D03*
X221000Y723000D03*
X218000Y801500D03*
X223500Y825500D03*
X228000Y825000D03*
X232000D03*
X227000Y858000D03*
X217000Y858500D03*
X222000Y853500D03*
Y858500D03*
Y863500D03*
Y893600D03*
X243755Y490890D03*
X242003Y506327D03*
X234755Y509700D03*
X245205Y504679D03*
X246613Y501365D03*
X237055Y513500D03*
X234185Y527138D03*
X248855Y532300D03*
X239555Y519500D03*
X247500Y829500D03*
X237953Y861453D03*
X259055Y500500D03*
X260288Y514589D03*
X264655Y511100D03*
X250055Y510800D03*
X256055Y531016D03*
X260555Y525500D03*
X253679Y523137D03*
X260605Y519245D03*
X263555Y534500D03*
X261255Y549000D03*
X265455Y544853D03*
X252055Y548760D03*
X257555Y549000D03*
X251000Y835500D03*
X251500Y855500D03*
X252000Y846500D03*
X252500Y851500D03*
X250362Y865000D03*
X253610Y863447D03*
X279997Y514179D03*
X275555Y531500D03*
X275055Y521825D03*
X266055Y531725D03*
X272571Y541150D03*
X278367Y535140D03*
X269555Y536000D03*
X271451Y544616D03*
X278676Y539500D03*
X270000Y870000D03*
Y865500D03*
X276500Y888500D03*
X280500Y955000D03*
X278050Y958500D03*
X296200Y94400D03*
X292525Y498780D03*
X292045Y504897D03*
X293273Y509500D03*
X282626Y516639D03*
X291530Y525407D03*
X283103Y520208D03*
X286588Y519305D03*
X292555Y533043D03*
X291755Y529000D03*
X286555Y524524D03*
X282555Y540700D03*
X283038Y536850D03*
X309500Y78500D03*
X313250Y85250D03*
X311500Y81500D03*
X314000Y102500D03*
X302000Y94300D03*
X299831Y144328D03*
X303677D03*
X305852Y163800D03*
X309698D03*
X299395Y449160D03*
X312925Y462560D03*
X298662Y479783D03*
X305055Y472500D03*
X302555Y476000D03*
X312773Y529878D03*
X313000Y582000D03*
X327000Y89500D03*
X323000D03*
X319309Y89503D03*
X317500Y101000D03*
X324200Y101900D03*
X330000Y118500D03*
X325929D03*
X321500D03*
X327100Y136294D03*
Y139857D03*
X326422Y152507D03*
Y148944D03*
X319800Y146898D03*
Y143052D03*
X322229Y218800D03*
X316129Y213000D03*
X328000Y285000D03*
X330555Y467500D03*
X325873Y477006D03*
X325854Y480606D03*
X317195Y493280D03*
X317255Y514170D03*
X330491Y525490D03*
X315725Y549790D03*
X329695Y534650D03*
X317758Y581297D03*
X329055Y569500D03*
X321780Y575000D03*
X314930Y585500D03*
X321500Y688000D03*
X333000Y90500D03*
X343000Y89000D03*
X339500Y75500D03*
X337500Y84250D03*
X342000Y102000D03*
X346000D03*
X334500Y118500D03*
X334600Y129468D03*
Y133031D03*
X343929Y320700D03*
X344929Y325500D03*
X342500Y340000D03*
X338500Y397500D03*
X336375Y452870D03*
X338985Y467405D03*
X343688Y509533D03*
X334055Y526000D03*
X347213Y546700D03*
X334555Y548500D03*
X341055Y534500D03*
X344655D03*
X345500Y556500D03*
X339888Y586388D03*
X346402Y653004D03*
X342500Y653000D03*
X335500Y868000D03*
X332129Y889371D03*
X331829Y885500D03*
X338000Y942000D03*
X339500Y960000D03*
X352000Y66000D03*
X357500Y79500D03*
Y75500D03*
X351929Y332500D03*
X364015Y468450D03*
X349575Y479503D03*
X349815Y475550D03*
X358797Y532258D03*
X354055Y534000D03*
X352095Y524040D03*
X362555Y534500D03*
X348255D03*
X360500Y588500D03*
X350000Y652878D03*
X362210Y876200D03*
X363480Y907783D03*
X362000Y904500D03*
X363000Y931500D03*
X359000D03*
X354000Y960000D03*
X363614Y971524D03*
X361000Y974000D03*
X360024Y979100D03*
X366600Y285800D03*
X377855Y300110D03*
X374000Y293500D03*
X372055Y364000D03*
X370275Y413540D03*
X371710Y406535D03*
X369555Y417500D03*
X370575Y409952D03*
X375055Y444500D03*
X367022Y482783D03*
X378255Y471840D03*
X379000Y531000D03*
X371000Y866500D03*
X376041Y866041D03*
X375500Y906000D03*
Y901500D03*
X365500Y916000D03*
X369341Y916117D03*
X371100Y926000D03*
X377000Y927500D03*
X372300Y918749D03*
X369500Y936500D03*
X368000Y932000D03*
X371000Y930000D03*
X376000Y960000D03*
X364396Y980109D03*
X366878Y977500D03*
X369200Y980252D03*
X372500Y977918D03*
X377464Y987493D03*
X377250Y982250D03*
X390000Y13500D03*
X385000D03*
X388000Y233500D03*
X388149Y229780D03*
X393429Y229500D03*
X395450Y265400D03*
X390100Y263600D03*
X387500Y261000D03*
X381500Y297000D03*
X395104Y291056D03*
X382455Y331870D03*
X393055Y451000D03*
Y447400D03*
X385463Y450948D03*
X386055Y454500D03*
X388885Y471100D03*
X381500Y534000D03*
X384046Y536546D03*
X396000Y714500D03*
X392500Y718500D03*
X391000Y866500D03*
X396500Y888500D03*
X396600Y895855D03*
X396330Y899705D03*
X396500Y904000D03*
X384000Y926500D03*
X389838Y942300D03*
X388500Y955250D03*
X390000Y946500D03*
X397900Y231800D03*
X399500Y240500D03*
X401855Y293500D03*
X408656Y291500D03*
X405555Y293500D03*
X406555Y320500D03*
X403255Y425950D03*
X404500Y877300D03*
X397600Y892000D03*
X399500Y901500D03*
X403250Y949000D03*
X408250Y949500D03*
X410500Y954500D03*
X405704Y952046D03*
X398250Y955000D03*
X400750Y952000D03*
X410000Y983500D03*
X410500Y987500D03*
X414000Y8000D03*
X418192Y114237D03*
X421000Y231500D03*
X424929Y264700D03*
X428100Y266500D03*
X419600Y282900D03*
X419455Y293000D03*
X416187Y294711D03*
X429500Y311000D03*
X425278Y802000D03*
X416046Y959546D03*
X414500Y948500D03*
X414215Y952089D03*
X422098Y948630D03*
X418500Y948500D03*
X413500Y957000D03*
X416000Y964000D03*
X420000D03*
X413600Y983500D03*
X438500Y9000D03*
X433929Y100000D03*
Y264300D03*
X439800Y284100D03*
X439200Y294550D03*
X432500Y301000D03*
X435000Y294000D03*
X444778Y802100D03*
X438278D03*
X431778Y802000D03*
X431278Y883000D03*
X444278D03*
X437778D03*
X432000Y933500D03*
X430500Y962000D03*
X459429Y106000D03*
X448929Y99500D03*
X450929Y118000D03*
X462500Y169000D03*
X455054Y179475D03*
X458429Y175590D03*
X456000Y243500D03*
X460000D03*
X461100Y260050D03*
X459055Y263500D03*
X456278Y802100D03*
X450778Y883000D03*
X460778D03*
X471290Y118361D03*
X469000Y113000D03*
X472990Y113350D03*
X462700Y120800D03*
X477291Y147500D03*
X477900Y153600D03*
X471000Y141000D03*
X477929Y158000D03*
X467600Y158400D03*
X465600Y162000D03*
X475216Y182917D03*
X470000Y188500D03*
X462679Y176900D03*
X466700Y259400D03*
X464055Y256500D03*
X463371Y290371D03*
X464200Y307838D03*
X463945Y349700D03*
X475778Y802100D03*
X462778D03*
X469278D03*
X473778Y883000D03*
X467278D03*
X488500Y114200D03*
X481429Y150000D03*
X491257Y315952D03*
X495103D03*
X487612Y318606D03*
X480278Y883000D03*
X488000Y904500D03*
X483500Y907500D03*
X499390Y153500D03*
X503500D03*
X503929Y146500D03*
X506429Y149500D03*
X495929Y164500D03*
X508500Y320000D03*
X504453Y314200D03*
X500607D03*
X496155Y321700D03*
X505922Y415371D03*
X506163Y419973D03*
X508100Y605500D03*
X506000Y610000D03*
X513200Y121450D03*
X513000Y156500D03*
X512000Y320000D03*
X519706Y314000D03*
X515860D03*
X527002Y319359D03*
X523348D03*
X526500Y346532D03*
Y342969D03*
Y352969D03*
X520500Y351500D03*
Y347937D03*
Y358937D03*
X526500Y356532D03*
X520500Y362500D03*
X533000Y153800D03*
X528500Y172000D03*
X539714Y179150D03*
X542500Y188500D03*
X537479Y197875D03*
X539073Y237300D03*
X531590Y297620D03*
X534500Y295500D03*
X528500Y310000D03*
X534629Y311171D03*
X534960Y321000D03*
X538614D03*
X529848Y325500D03*
X533502D03*
X550500Y188000D03*
X560500Y186000D03*
X555500Y194000D03*
X559500D03*
X545000Y195000D03*
X549926Y204000D03*
X557275Y214918D03*
X553675Y215913D03*
X550075D03*
X559961Y209419D03*
X546916Y217641D03*
X548000Y231000D03*
X547746Y225303D03*
X559971Y237753D03*
X553555Y321000D03*
X560253Y329500D03*
X557061Y334194D03*
X553155Y334300D03*
X548000Y369500D03*
X555935Y363000D03*
X559500Y604500D03*
X572000Y189000D03*
X571398Y183602D03*
X561429Y174441D03*
X575500Y198400D03*
X576650Y204500D03*
X563100Y194000D03*
X568158Y206455D03*
X571461Y207887D03*
X569000Y217000D03*
X569127Y213100D03*
X564583Y206028D03*
X577119Y233139D03*
X564631Y234356D03*
X569322Y234220D03*
X573179Y233535D03*
X575425Y228505D03*
X563704Y272000D03*
X563555Y333000D03*
X564215Y369339D03*
X566430Y366500D03*
X569555Y364000D03*
X562555Y364500D03*
X587175Y202525D03*
X591413Y199087D03*
X583500Y204500D03*
X585325Y198000D03*
X583325Y208500D03*
X583204Y236805D03*
X580709Y232091D03*
X619876Y195000D03*
X617828Y303250D03*
X613962D03*
X623500Y576500D03*
X622500Y608500D03*
X633578Y303250D03*
X629712D03*
X642800Y433587D03*
X641500Y449500D03*
X636500Y444800D03*
X640500Y444500D03*
X635325Y457500D03*
X628524Y591976D03*
X649323Y303250D03*
X645457D03*
X652714Y428214D03*
X647500Y425500D03*
X645500Y459500D03*
X654300Y490300D03*
X674469Y99380D03*
X674358Y103170D03*
X665073Y303250D03*
X661207D03*
X669025Y441725D03*
X660500Y436538D03*
X669462Y472500D03*
X667056Y475500D03*
X673010Y474436D03*
X673300Y579000D03*
X669000D03*
X663500Y610500D03*
X674688Y696751D03*
X670474Y808700D03*
X671500Y861000D03*
X673500Y864000D03*
X672000Y967750D03*
X667000Y969700D03*
X666750Y961550D03*
X685519Y55019D03*
X676748Y52000D03*
X684861Y58584D03*
X686000Y62000D03*
X684197Y74703D03*
X687500Y440500D03*
X677500Y472500D03*
X688500Y606000D03*
X683000Y603950D03*
X677500Y612000D03*
X680000Y640000D03*
X691000Y704500D03*
X677500Y699000D03*
X682968Y758284D03*
X677500Y773500D03*
X678468Y805284D03*
X691300Y807300D03*
X679000Y865050D03*
X676500Y967750D03*
X706716Y82448D03*
X705500Y575600D03*
X702918Y782734D03*
X704000Y892500D03*
X716034Y53966D03*
X716466Y65466D03*
X711216Y82402D03*
X720216Y82138D03*
X711500Y179400D03*
X725000Y452300D03*
X720700Y564200D03*
X717036Y563783D03*
X709750Y585200D03*
X719918Y754734D03*
X715118Y776134D03*
X717468Y810784D03*
X722000Y808500D03*
X720500Y860000D03*
X710750Y863250D03*
X714000Y867500D03*
X714500Y891000D03*
X740500Y75000D03*
X728100Y213800D03*
X732500Y455500D03*
X736000Y464500D03*
X728500Y482500D03*
X730000Y536500D03*
X733500Y568500D03*
X729900D03*
X741500Y582450D03*
X737000Y583640D03*
X740768Y763984D03*
X735500Y771984D03*
X736000Y810500D03*
X733768Y800734D03*
X741050Y869500D03*
X740000Y886000D03*
X737290Y903000D03*
X733000Y969700D03*
X754500Y67500D03*
X747000Y210000D03*
X755697Y303250D03*
X751484Y540600D03*
X755000Y727500D03*
X757500Y743500D03*
X757000Y896400D03*
X749500Y974300D03*
X759563Y303250D03*
X771447D03*
X773500Y326000D03*
X758500Y457000D03*
X772024Y478976D03*
X774500Y489500D03*
X760500D03*
X766000Y635000D03*
X763000Y648000D03*
X767000Y648500D03*
X771000Y689500D03*
X760500Y707950D03*
X768000Y728000D03*
X763500Y839500D03*
X768000Y833000D03*
X766750Y849250D03*
X774500Y890500D03*
X775748Y188500D03*
X789500Y235837D03*
X787192Y303250D03*
X775313D03*
X779000Y458000D03*
X776000Y478828D03*
X788774Y482774D03*
X786500Y575688D03*
X786032Y570468D03*
X783500Y649000D03*
X784804Y673304D03*
X779500Y705000D03*
X785000Y892000D03*
X785500Y969700D03*
X796000Y167600D03*
X795500Y163408D03*
X802942Y303250D03*
X791058D03*
X806808D03*
X798000Y400500D03*
X796074Y479000D03*
X803500Y655000D03*
X798000Y706000D03*
X802000Y724000D03*
X801750Y867500D03*
X818000Y240900D03*
X821100Y348480D03*
Y352480D03*
X808500Y363500D03*
X823500Y480000D03*
X814500Y472500D03*
X823500Y556500D03*
X815900Y564000D03*
X819500D03*
X821250Y845750D03*
X810500Y851000D03*
X819000Y868500D03*
X832000Y137500D03*
X826198Y239950D03*
X833555Y262000D03*
X833500Y613000D03*
X835000Y719000D03*
X826500Y743000D03*
X824560Y868560D03*
X856055Y262500D03*
X842555Y262000D03*
X850540Y346070D03*
X844410Y346360D03*
X847500Y352000D03*
X849500Y622000D03*
X846500Y710000D03*
X845500Y865000D03*
X873000Y68500D03*
X870100Y237500D03*
X869544Y226000D03*
X860400Y231000D03*
X860555Y262500D03*
X863820Y363880D03*
X868820D03*
X870500Y444000D03*
Y448000D03*
X857500Y485500D03*
X862500Y621250D03*
X859500Y629500D03*
X872000Y636000D03*
X867500Y655200D03*
X860718Y683684D03*
X877860Y316330D03*
X887950Y359730D03*
X874910Y360160D03*
X879510Y355410D03*
X887940Y380200D03*
X878000Y404500D03*
X876000Y435500D03*
X886300Y443100D03*
X882700D03*
X885000Y438700D03*
X877000Y479500D03*
X876000Y631700D03*
X881000Y710000D03*
X899000Y312500D03*
X898000Y316000D03*
X903480Y324230D03*
X893500Y427000D03*
X893600Y443100D03*
X889900D03*
X903075Y472000D03*
X918420Y449130D03*
X907000Y465050D03*
X917000Y752500D03*
X923000Y51500D03*
X924465Y388465D03*
X936030Y457540D03*
X937000Y489000D03*
X935400Y597300D03*
X939500Y352000D03*
X953500Y348927D03*
X944000Y434000D03*
X958500Y187500D03*
X957990Y191064D03*
X962000Y251500D03*
X965500Y260500D03*
X963500Y256000D03*
X959500Y351688D03*
X965000Y364500D03*
X964000Y354000D03*
X970382Y455872D03*
X961700Y477500D03*
X957500Y585500D03*
X961500D03*
X970750Y703000D03*
X980490Y198827D03*
X982075Y439500D03*
X973015Y453416D03*
X977000Y547500D03*
X982500Y549500D03*
X978000Y554000D03*
X975000Y701000D03*
X1003000Y59500D03*
X988900Y434800D03*
X992690Y466750D03*
X996910Y466560D03*
X994500Y491000D03*
X1003422Y490578D03*
X992000Y505500D03*
X990500Y536500D03*
X998500Y591500D03*
X989000Y659500D03*
Y757150D03*
X1016500Y87500D03*
X1020500Y124500D03*
Y142000D03*
X1014000Y487000D03*
X1007500Y507000D03*
X1008500Y533400D03*
X1013500Y559000D03*
X1016900Y561000D03*
X1017982Y585018D03*
X1007532Y902468D03*
X1033500Y118000D03*
X1025500Y129500D03*
X1033500Y124000D03*
X1037085Y137000D03*
X1023000Y155000D03*
X1028000Y164500D03*
X1023600Y173000D03*
X1031524Y218476D03*
X1033900Y225500D03*
X1027426Y346500D03*
X1023000Y347000D03*
X1031000Y348500D03*
Y355950D03*
X1030000Y403500D03*
X1036500Y581500D03*
X1035000Y594500D03*
X1021000Y588500D03*
X1025500Y657000D03*
X1023500Y727000D03*
X1037000Y734000D03*
X1024387Y738230D03*
X1035000Y800000D03*
Y804500D03*
X1032657Y901500D03*
X1027716Y914784D03*
X1032200Y921500D03*
X1045031Y138031D03*
X1041485Y137409D03*
X1040000Y182000D03*
X1052500Y187500D03*
X1037500Y225500D03*
X1040000Y579000D03*
X1038000Y604000D03*
X1053500Y620500D03*
X1046000Y644000D03*
X1038000Y635000D03*
X1042450Y648500D03*
X1045500Y639500D03*
X1050092Y655052D03*
X1042400Y684500D03*
X1052500Y693000D03*
X1052678Y704084D03*
X1038500Y706500D03*
X1052500Y709000D03*
Y700000D03*
X1041410Y708804D03*
Y704224D03*
X1052648Y712724D03*
X1040208Y745020D03*
X1052500Y773350D03*
X1044000Y763940D03*
X1064000Y80000D03*
X1055500D03*
X1059500D03*
X1068000D03*
Y76000D03*
X1064000D03*
X1059500D03*
X1055500D03*
X1068500Y118500D03*
X1069000Y124500D03*
X1060900Y173534D03*
X1056500Y194000D03*
X1061000Y211500D03*
X1055000Y219284D03*
X1060766Y395426D03*
X1061200Y399000D03*
X1068300Y488700D03*
X1059000Y558190D03*
X1058000Y599500D03*
X1056000Y604000D03*
X1058500Y660900D03*
X1054900D03*
X1070000Y650725D03*
X1058350Y681450D03*
X1068500Y677000D03*
X1054500Y697000D03*
X1068500Y687000D03*
X1066000Y717000D03*
X1059800Y719740D03*
X1054000Y735000D03*
X1056350Y748000D03*
X1063000Y780000D03*
X1072000Y136000D03*
X1080300Y191000D03*
X1084500Y202500D03*
X1078500Y464000D03*
X1080000Y520000D03*
X1081000Y548000D03*
Y544400D03*
X1084599Y544520D03*
X1086000Y556000D03*
X1071500Y589000D03*
X1085000Y661000D03*
X1074000Y677000D03*
X1073500Y672000D03*
X1074000Y683000D03*
X1074500Y694754D03*
X1074426Y687255D03*
X1074389Y691155D03*
X1074000Y699500D03*
X1074148Y711624D03*
X1074600Y707724D03*
X1074000Y703500D03*
X1073384Y722384D03*
X1073000Y730834D03*
Y726444D03*
X1074288Y715534D03*
X1084300Y741874D03*
X1077500Y745374D03*
X1072000Y743500D03*
X1084000Y748099D03*
X1070098Y764500D03*
X1083700Y835725D03*
X1077000Y943075D03*
X1083200Y956500D03*
X1093894Y126500D03*
X1090028D03*
X1092500Y461500D03*
X1098500Y465000D03*
X1089000Y508500D03*
X1100575Y559075D03*
X1098000Y562000D03*
X1091425Y551425D03*
X1093500Y640000D03*
X1094500Y657500D03*
X1091000Y692519D03*
X1090257Y724253D03*
X1087600Y727029D03*
X1094853Y726853D03*
X1095500Y812000D03*
X1097500Y849000D03*
X1089000Y867284D03*
X1099623Y869123D03*
X1097423Y906546D03*
X1093500Y905500D03*
X1110318Y275600D03*
X1111500Y517500D03*
X1107500Y580000D03*
X1114883Y591925D03*
X1106000Y609500D03*
Y605500D03*
X1111500Y718500D03*
X1107000Y763000D03*
X1110300Y790000D03*
X1111834Y813334D03*
X1113500Y824500D03*
X1111000Y836000D03*
X1107160Y843160D03*
X1128000Y288500D03*
X1132300Y288800D03*
X1130000Y361500D03*
X1124327Y465391D03*
X1123500Y521500D03*
X1128149Y525261D03*
X1130928Y527550D03*
X1132000Y562000D03*
X1125600Y570600D03*
X1135000Y597000D03*
X1132222Y593278D03*
X1119487Y588088D03*
X1122353Y590268D03*
X1125000Y603050D03*
X1134000Y613500D03*
X1126000Y627329D03*
X1131000Y631000D03*
X1121500Y621600D03*
X1130490Y627436D03*
X1125041Y631000D03*
X1120500Y729500D03*
X1124000Y729000D03*
X1128430Y749640D03*
X1126642Y785505D03*
X1123200Y783900D03*
X1130030Y820000D03*
X1146500Y267000D03*
X1146000Y258500D03*
X1151000Y264500D03*
X1146500Y275500D03*
X1136100Y288900D03*
X1136450Y294650D03*
X1150640Y359860D03*
X1146640D03*
X1142640D03*
X1151500Y522000D03*
X1143500Y542000D03*
X1147500D03*
X1136075Y559075D03*
X1145900Y579800D03*
X1136500Y592500D03*
X1139632Y594441D03*
X1140500Y589000D03*
X1141100Y585400D03*
X1147400Y729900D03*
X1153700Y267700D03*
X1156100Y316405D03*
Y312795D03*
X1165000Y308175D03*
Y304565D03*
X1161530Y360430D03*
X1157480Y361620D03*
X1157700Y368500D03*
X1160058Y364558D03*
X1155400Y371500D03*
X1164000Y397000D03*
X1168000Y390250D03*
X1166500Y415500D03*
X1155500Y450758D03*
Y446892D03*
X1161000Y541500D03*
X1154000Y589000D03*
X1164500Y628723D03*
X1159075Y630600D03*
X1154847Y630908D03*
X1156377Y627623D03*
X1153500Y784190D03*
X1164500Y857500D03*
X1162000Y960625D03*
X1181427Y251500D03*
X1180677Y256500D03*
X1173777Y290125D03*
X1169777D03*
X1173125Y323716D03*
X1169515D03*
X1184000Y351500D03*
X1174500Y366000D03*
X1182000Y357000D03*
X1174400Y356500D03*
X1178000D03*
X1175125Y370000D03*
X1174500Y404000D03*
X1173500Y422500D03*
Y554000D03*
X1181350Y595450D03*
X1169075Y613500D03*
X1183000Y628000D03*
X1177100Y624750D03*
X1178500Y653100D03*
X1184500Y749500D03*
Y772782D03*
X1173200Y789500D03*
X1177000Y860000D03*
X1169000Y856000D03*
X1181500Y949000D03*
X1188000Y248500D03*
X1192743Y289800D03*
X1188877D03*
X1199685Y344588D03*
X1196075D03*
X1189000Y421500D03*
X1195000Y428000D03*
X1197675Y533125D03*
X1191000Y528000D03*
X1189000Y533825D03*
X1194564Y530936D03*
X1185500Y548075D03*
X1200500Y547925D03*
X1186000Y615500D03*
X1196000Y605800D03*
X1184956Y619272D03*
X1191000Y663000D03*
X1193804Y657175D03*
X1191000Y667000D03*
X1197500Y665500D03*
X1199551Y683968D03*
X1195937Y683849D03*
X1189890Y684053D03*
X1192937Y683911D03*
X1196500Y745500D03*
Y736687D03*
X1192500Y745500D03*
X1192038Y761481D03*
X1188500Y773000D03*
X1184975Y767500D03*
X1194000Y764500D03*
X1190000Y767500D03*
X1196000Y847500D03*
Y874500D03*
X1207500Y239500D03*
X1210800Y379700D03*
X1216000Y390000D03*
X1209500Y404500D03*
X1216500Y439500D03*
X1212500Y436000D03*
X1217000Y452500D03*
X1210000Y507500D03*
X1209500Y514000D03*
X1213100D03*
X1214450Y509000D03*
X1206400Y536800D03*
X1210000D03*
X1201500Y535000D03*
X1205240Y568760D03*
X1207700Y605500D03*
X1208500Y623000D03*
X1204500Y659500D03*
X1203181Y683968D03*
X1206781Y684003D03*
X1213598Y699164D03*
X1216000Y702500D03*
X1206500Y757000D03*
X1213500Y756000D03*
X1202218Y811282D03*
X1211000Y847500D03*
X1208940Y874560D03*
X1227500Y500500D03*
Y504246D03*
X1220500Y513000D03*
X1229500Y533000D03*
X1231632Y537000D03*
X1221500Y539500D03*
X1233000Y554502D03*
X1219200Y564600D03*
X1221500Y633000D03*
X1231450Y677500D03*
X1229000Y716000D03*
Y726500D03*
Y719600D03*
Y740000D03*
X1230219Y747469D03*
X1232000Y738000D03*
X1234000Y747500D03*
X1224500Y757500D03*
X1228547Y772547D03*
Y778453D03*
X1231000Y768500D03*
X1221000Y764750D03*
X1233000Y782500D03*
X1223500Y798500D03*
X1223000Y826500D03*
X1218500Y834500D03*
X1229807Y847000D03*
X1239000Y190500D03*
X1240000Y209449D03*
X1243000Y431500D03*
X1250000Y422000D03*
X1234500Y439000D03*
X1248250Y439250D03*
X1250450Y462000D03*
X1242000Y459000D03*
X1247800Y472750D03*
X1246750Y476250D03*
X1249000Y509500D03*
X1249251Y528688D03*
X1235482Y546982D03*
X1240000Y546500D03*
Y542900D03*
X1240173Y550327D03*
X1250500Y567000D03*
X1241000Y631500D03*
X1237500Y675500D03*
X1239500Y671000D03*
X1235000Y682000D03*
X1244371Y733129D03*
X1236500Y737925D03*
X1243000Y743000D03*
X1241000Y734500D03*
X1240016Y761500D03*
X1238000Y764500D03*
X1249500Y765500D03*
X1248950Y769500D03*
X1238047Y791953D03*
X1240045Y788957D03*
X1241984Y796000D03*
X1243953Y789000D03*
X1240660Y829000D03*
X1235258Y820758D03*
X1257000Y33000D03*
X1260677Y237000D03*
X1264177Y233500D03*
X1256000Y252000D03*
X1262558Y254942D03*
X1261677Y241500D03*
Y245500D03*
X1264500Y260000D03*
X1254944Y268567D03*
X1263000Y278500D03*
X1250677Y287500D03*
Y283500D03*
X1254944Y272433D03*
X1260577Y299968D03*
Y296102D03*
X1253477Y312800D03*
X1253577Y308800D03*
X1253177Y320500D03*
Y324500D03*
X1265000Y426500D03*
X1253000Y511000D03*
X1251500Y531500D03*
X1260500Y546400D03*
X1263500Y550000D03*
X1258000Y555400D03*
X1255000Y609300D03*
X1266500Y617500D03*
X1265000Y647500D03*
X1257500Y635500D03*
X1265000Y661000D03*
Y657000D03*
X1265500Y652500D03*
X1257100Y664300D03*
X1263121Y678621D03*
X1259000Y678950D03*
X1262300Y670700D03*
X1266000Y665600D03*
X1262500Y699825D03*
X1253500Y778465D03*
X1257950Y809250D03*
X1279500Y150500D03*
X1276500Y234000D03*
X1267677Y232500D03*
X1280500Y338000D03*
Y404550D03*
X1280000Y420500D03*
X1272500Y466600D03*
X1274500Y606000D03*
X1278500Y603500D03*
X1271000Y617500D03*
X1279340Y618660D03*
X1272451Y642500D03*
X1272502Y638900D03*
X1281268Y661780D03*
X1268805Y655405D03*
X1282500Y669561D03*
X1273702Y667662D03*
X1275885Y670525D03*
X1267500Y675000D03*
Y684878D03*
X1281500Y713000D03*
X1279000Y746575D03*
X1267500Y783000D03*
X1269500Y835000D03*
X1299500Y236000D03*
X1292500Y402000D03*
X1289000Y415500D03*
X1285700Y529700D03*
X1293960Y528740D03*
X1294600Y524200D03*
X1291300Y540900D03*
X1294000Y587500D03*
X1288335Y594048D03*
X1287482Y590500D03*
X1293500Y593000D03*
X1285557Y585000D03*
X1289570Y597430D03*
X1284825Y621500D03*
X1294000Y628000D03*
X1299000Y641500D03*
X1296000Y638500D03*
X1290500Y635500D03*
X1286500Y652500D03*
X1297500Y665000D03*
X1289500Y669000D03*
X1284490Y710936D03*
X1296500Y830782D03*
X1306000Y43000D03*
X1304050Y296500D03*
X1307500Y320500D03*
X1308000Y311000D03*
X1312750Y314000D03*
X1306000Y329000D03*
Y334500D03*
Y338500D03*
X1311000Y463500D03*
X1302000Y475000D03*
X1304700Y536000D03*
X1302500Y559500D03*
X1307000Y573412D03*
X1306817Y592412D03*
X1310500Y625000D03*
X1312000Y645784D03*
X1310425Y660062D03*
X1311100Y656400D03*
X1304400Y661400D03*
X1311700Y681500D03*
X1312115Y672000D03*
X1311000Y677284D03*
X1311300Y687500D03*
X1313500Y710000D03*
X1305000Y739750D03*
X1308100Y748200D03*
X1312500Y838000D03*
X1305000Y850500D03*
X1312000D03*
X1314500Y921500D03*
X1322500Y299000D03*
X1324000Y290500D03*
X1322500Y337000D03*
X1317000Y336000D03*
X1330500Y441000D03*
X1332000Y459250D03*
X1323500Y452500D03*
X1326617Y594412D03*
X1325950Y599000D03*
X1329317Y626512D03*
X1328000Y649000D03*
X1328968Y679684D03*
X1323500Y702000D03*
X1322000Y705500D03*
X1325250Y834250D03*
X1316500Y839000D03*
X1317000Y850500D03*
X1318113Y846371D03*
X1339000Y54000D03*
X1347000Y48000D03*
X1342500Y51000D03*
X1333100Y58600D03*
X1343500Y112000D03*
X1336500Y270874D03*
X1339000Y274000D03*
X1339500Y305500D03*
X1341873Y344873D03*
X1335000Y443250D03*
X1335317Y575412D03*
X1342648Y612412D03*
X1347617Y610412D03*
X1334500Y636000D03*
Y669000D03*
X1352000Y85500D03*
X1349500Y112000D03*
X1350000Y276500D03*
X1350084Y296500D03*
X1353000Y390000D03*
Y402000D03*
X1362500Y459000D03*
X1353500Y466500D03*
X1351000Y455750D03*
X1356817Y579012D03*
X1364617Y592912D03*
X1360200Y614800D03*
X1353517Y627512D03*
X1357300Y617700D03*
X1379500Y274500D03*
X1381500Y292000D03*
X1376000D03*
X1379500Y314000D03*
X1370500Y356500D03*
X1374500Y462800D03*
X1367617Y570012D03*
X1390004Y122600D03*
X1384500Y274500D03*
Y331500D03*
G54D47*
X1379862Y108465D03*
Y119095D03*
G54D43*
X1258504Y329331D03*
Y368701D03*
G54D42*
X1224016Y386221D03*
G54D12*
X21220Y373228D03*
X96890D03*
X157480Y283071D03*
X220472D03*
G54D18*
X121890Y269528D03*
X131890D03*
X141890D03*
X1346396Y21656D03*
X1338526D03*
X1346396Y29526D03*
X1362146Y21656D03*
X1354271D03*
X1362146Y29526D03*
X1354271D03*
X1377896Y21656D03*
X1370021D03*
X1377896Y29526D03*
X1370021D03*
X1385766Y21656D03*
Y29526D03*
G54D19*
X121000Y545500D03*
X146364Y296000D03*
X156500Y939500D03*
X162000D03*
X168000Y575000D03*
Y580000D03*
X178000Y590000D03*
X167500Y939500D03*
X172500D03*
X177500D03*
X182000D03*
X188000D03*
X193500D03*
X199500D03*
X207100Y703600D03*
X222000Y703500D03*
X224000Y875000D03*
X225500Y879500D03*
X225000Y920500D03*
X232000Y921000D03*
X227500Y957500D03*
Y963500D03*
X247500Y883000D03*
X243000D03*
X246968Y957784D03*
X233468Y957284D03*
X239968Y957784D03*
X246968Y963784D03*
X239968D03*
X233468D03*
X259000Y211000D03*
Y206000D03*
X262500Y208500D03*
X252000Y883000D03*
X256500D03*
X261000D03*
X265500D03*
X252000Y957500D03*
X252500Y963500D03*
X281800Y183700D03*
Y188500D03*
X281900Y178500D03*
X278500Y965000D03*
X277500Y969500D03*
X272500D03*
X268000D03*
X296000Y105000D03*
X285800Y180800D03*
X285600Y186100D03*
X285500Y330000D03*
X286000Y336000D03*
X306000Y105000D03*
X301000D03*
X310929Y257500D03*
X311429Y334500D03*
X307429Y336000D03*
Y331500D03*
X320500Y11000D03*
X316000D03*
X324000Y24000D03*
Y19500D03*
Y15000D03*
X330500Y38500D03*
Y33500D03*
X315929Y253000D03*
Y257500D03*
X344000Y27000D03*
X336000D03*
X337500Y102000D03*
X349000Y38500D03*
Y33500D03*
X351929Y266000D03*
X357661Y434216D03*
X364055Y428500D03*
X361055Y431500D03*
X362500Y608500D03*
X355500D03*
Y614000D03*
X362500D03*
X370500Y72100D03*
X376500Y608500D03*
X369500D03*
Y614000D03*
X376500D03*
X393800Y25100D03*
X389300Y20100D03*
X393800D03*
X384800Y25100D03*
X389300D03*
X384800Y20100D03*
X391000Y35500D03*
X395500D03*
X393900Y30400D03*
X389400D03*
X384900D03*
X386000Y53000D03*
X381500D03*
Y58000D03*
X398300Y20100D03*
Y25100D03*
X400000Y35500D03*
X398400Y30400D03*
X398000Y39500D03*
X403155Y437600D03*
X445395Y317610D03*
X432678Y827300D03*
X430778Y864000D03*
X453878Y824900D03*
X456278Y866500D03*
X467000Y118500D03*
X482429Y139000D03*
X482778Y832000D03*
X482278Y867500D03*
X495000Y883000D03*
X501000Y876000D03*
X499000Y883000D03*
X516000Y134000D03*
X519929Y135500D03*
X521055Y528500D03*
Y533500D03*
X516555Y528500D03*
Y533500D03*
X526055D03*
X526000Y524500D03*
Y529000D03*
X521000Y524000D03*
X521055Y544000D03*
Y548900D03*
X516555Y543500D03*
X516655Y548900D03*
X521055Y538500D03*
X516555Y539000D03*
X526055Y538500D03*
Y544000D03*
Y548900D03*
X516500Y556000D03*
X591000Y253500D03*
Y262500D03*
X586000Y267000D03*
Y262500D03*
X591000Y258000D03*
X586150Y383000D03*
X586200Y378500D03*
X581950Y383000D03*
X582000Y378500D03*
X590500Y383000D03*
X586150Y396000D03*
X590500D03*
X581950D03*
X586150Y409500D03*
X581950D03*
X590500D03*
X582700Y431500D03*
X590500Y423500D03*
X586150D03*
X587000Y431500D03*
X578500D03*
X581950Y423500D03*
X582200Y439500D03*
X578000D03*
X586500D03*
X593500Y648500D03*
Y659500D03*
Y654000D03*
X595500Y253500D03*
Y258000D03*
X610000Y415500D03*
Y434000D03*
Y428500D03*
Y422000D03*
X610100Y439500D03*
X602500Y465900D03*
X608000Y465800D03*
X602500Y470100D03*
X608000Y470300D03*
X601000Y543000D03*
X599500Y648500D03*
Y654000D03*
Y659500D03*
X609500Y778500D03*
X603000D03*
Y785000D03*
X609000Y870000D03*
X604000Y877500D03*
X609211Y877611D03*
X614200Y415500D03*
X614500Y434000D03*
X614200Y422000D03*
Y428500D03*
X614300Y439500D03*
X620000Y465800D03*
X613500D03*
X626500D03*
X613500Y470000D03*
X620000D03*
X626500D03*
Y557350D03*
X637500Y367900D03*
X630500Y368500D03*
X642000D03*
X647500D03*
X653500D03*
X659500D03*
X645500Y481000D03*
X674666Y82002D03*
X670998Y116010D03*
X665000Y368500D03*
X670000Y395000D03*
X670500Y414000D03*
X685898Y133380D03*
X682418Y129980D03*
X685000Y150500D03*
X701949Y118331D03*
X701828Y129550D03*
X698500Y132500D03*
X697248Y128000D03*
X719500Y185600D03*
X725000Y189000D03*
X720000Y849000D03*
X721900Y852750D03*
X730748Y99500D03*
X740000Y109534D03*
X732248Y140000D03*
X731716Y156500D03*
X736000Y142000D03*
X740000Y681000D03*
X740500Y755000D03*
X739900Y760000D03*
X757000Y435500D03*
X752100Y435600D03*
X751500Y431000D03*
X756500D03*
X757802Y474000D03*
X773000Y339500D03*
X761600Y435600D03*
X761500Y431000D03*
X766000D03*
X770000Y677000D03*
Y681500D03*
X767000Y845000D03*
X773000Y917000D03*
Y921500D03*
Y927000D03*
X767500D03*
X771000Y958500D03*
X766600D03*
X762100Y958600D03*
X771500Y963500D03*
X767100D03*
X762600Y963600D03*
X771400Y968900D03*
X767000D03*
X762500Y969000D03*
X777500Y339500D03*
X782400Y339400D03*
X782600Y411000D03*
X792000Y356500D03*
X801500Y573000D03*
X819000Y473000D03*
X829500Y373500D03*
Y380000D03*
Y385500D03*
X848600Y517100D03*
X843100Y517000D03*
X843200Y512800D03*
X843300Y507900D03*
X848800Y508000D03*
X848700Y512900D03*
X854500Y778000D03*
X850000D03*
X854500Y783000D03*
X850000D03*
X858500Y656500D03*
X879736Y290000D03*
X875500Y290500D03*
X878500Y294178D03*
X884000Y396500D03*
X879500D03*
X889000Y617000D03*
X895000Y96000D03*
X899500Y92500D03*
X899000Y405500D03*
X894000D03*
X899000Y410500D03*
X894000D03*
X895000Y617500D03*
X930500Y219000D03*
X936500D03*
X930500Y232000D03*
X936500D03*
Y225500D03*
X930500D03*
Y536500D03*
X943500Y488000D03*
X966000Y209500D03*
X961000Y212500D03*
X963500Y488000D03*
Y536500D03*
Y654500D03*
X958000D03*
Y659500D03*
X963500D03*
X969000Y655100D03*
Y659500D03*
X981000Y386500D03*
X985000Y388000D03*
X980500Y391000D03*
X984500Y392500D03*
X974500Y655100D03*
Y659500D03*
X1004500Y84000D03*
X1013500D03*
X1009000D03*
X1016500Y75500D03*
X1011500Y642000D03*
Y648000D03*
X1022500Y51500D03*
X1034500D03*
X1028000D03*
X1021000Y75500D03*
X1033000Y290000D03*
X1027500D03*
X1027700Y294200D03*
X1033200D03*
X1035500Y825500D03*
Y830000D03*
X1053000Y228000D03*
X1046000Y290000D03*
X1039500D03*
X1039700Y294200D03*
X1046200D03*
X1040000Y825500D03*
X1044500D03*
X1049000D03*
X1053400D03*
X1040000Y830000D03*
X1057000Y229500D03*
X1056716Y224500D03*
X1060000Y929500D03*
X1086000Y187500D03*
Y192500D03*
X1079000Y434000D03*
X1085000D03*
X1079100Y429000D03*
X1101500Y461500D03*
X1102500Y762500D03*
X1097500D03*
X1102500Y767400D03*
X1097500D03*
X1093000Y766500D03*
X1097500Y797500D03*
X1106600Y753000D03*
X1134000Y229000D03*
X1128500D03*
X1129000Y502500D03*
X1123500D03*
Y507500D03*
X1129000D03*
X1135500D03*
Y502500D03*
X1141000Y507500D03*
Y502500D03*
X1161500Y222000D03*
X1166500D03*
X1160500Y242000D03*
Y246500D03*
X1165000Y242000D03*
Y246500D03*
X1171000Y222000D03*
X1176000D03*
X1169000Y398000D03*
X1171000Y394000D03*
X1170500Y461000D03*
X1173100Y499200D03*
X1182000Y816000D03*
X1181500Y820500D03*
X1177000D03*
X1199100Y226600D03*
X1194900D03*
X1195000Y422500D03*
X1194000Y484000D03*
X1189500D03*
X1194000Y488500D03*
X1189500D03*
Y492900D03*
X1194000Y493000D03*
X1188500Y500000D03*
X1195920Y753700D03*
X1203500Y193800D03*
Y198000D03*
X1208000D03*
Y193800D03*
X1204000Y206000D03*
X1208500Y207000D03*
X1204000Y210500D03*
Y215000D03*
X1207500Y225000D03*
X1203300Y226600D03*
X1217000Y537000D03*
X1216500Y710125D03*
X1249300Y166000D03*
X1240600Y167000D03*
X1240700Y171200D03*
X1240800Y179800D03*
X1240700Y175500D03*
Y184000D03*
X1241000Y219000D03*
X1239500Y227500D03*
X1242000Y223500D03*
X1244000Y227500D03*
X1246000Y263500D03*
X1263000Y717000D03*
X1287500Y428000D03*
X1308500Y771500D03*
X1303000D03*
X1314000D03*
X1324500Y345400D03*
Y341000D03*
X1329000Y341100D03*
Y345500D03*
X1323000Y368000D03*
X1327500D03*
X1332000D03*
Y372400D03*
X1327500D03*
X1323000D03*
X1338000Y341100D03*
X1333500D03*
Y345500D03*
X1338000D03*
X1358500Y346500D03*
Y351000D03*
X1354000D03*
Y346500D03*
X1354500Y480500D03*
Y475000D03*
X1360500D03*
Y480500D03*
X1354500Y486500D03*
X1360500D03*
X1360000Y631500D03*
X1355500Y631000D03*
X1358000Y626000D03*
X1357500Y635500D03*
X1351000Y677000D03*
Y672000D03*
X1355000Y674500D03*
X1354500Y669000D03*
X1371500Y254000D03*
X1366000D03*
X1371500Y264000D03*
X1366000D03*
X1371500Y259500D03*
X1366000D03*
G54D22*
X180118Y729409D03*
Y739409D03*
X200118Y729409D03*
X190118D03*
X210118D03*
X220118D03*
X250118D03*
X240118D03*
G54D36*
X599941Y70118D03*
X607933D03*
X595905Y80118D03*
X603897D03*
X611889D03*
X615925Y70118D03*
X623917D03*
X627953Y80118D03*
X631909Y70118D03*
X639901D03*
X635945Y80118D03*
X643937D03*
G54D31*
X545079Y290355D03*
X560829D03*
X549014Y298230D03*
X556889Y308070D03*
X552954Y315945D03*
X549014Y308070D03*
X576574Y290355D03*
X564764Y298230D03*
X572639Y308070D03*
X568699Y315945D03*
X592324Y290355D03*
X580514Y298230D03*
X588384Y308070D03*
X584449Y315945D03*
X608069Y290355D03*
X596259Y298230D03*
X604134Y308070D03*
X600199Y315945D03*
X627754Y298230D03*
X623819Y290355D03*
X612009Y298230D03*
X619884Y308070D03*
X615944Y315945D03*
X643504Y298230D03*
X639569Y290355D03*
X635629Y308070D03*
X631694Y315945D03*
X659254Y298230D03*
X655314Y290355D03*
X651379Y308070D03*
X647439Y315945D03*
X674999Y298230D03*
X671064Y290355D03*
X667124Y308070D03*
X663189Y315945D03*
X690749Y298230D03*
X686809Y290355D03*
X682874Y308070D03*
X678939Y315945D03*
X706494Y298230D03*
X702559Y290355D03*
X698624Y308070D03*
X694684Y315945D03*
X722244Y298230D03*
X718309Y290355D03*
X726179Y315945D03*
X714369Y308070D03*
X710434Y315945D03*
X737994Y298230D03*
X734054Y290355D03*
X741929Y315945D03*
X730119Y308070D03*
X753739Y298230D03*
X749804Y290355D03*
X757679Y315945D03*
X745864Y308070D03*
X769489Y298230D03*
X765549Y290355D03*
X773424Y315945D03*
X761614Y308070D03*
X785234Y298230D03*
X781299Y290355D03*
X789174Y315945D03*
X777364Y308070D03*
X800984Y298230D03*
X797049Y290355D03*
X804919Y315945D03*
X793109Y308070D03*
X816734Y298230D03*
X812794Y290355D03*
X820669Y315945D03*
X808859Y308070D03*
X840354Y298230D03*
X836419Y290355D03*
X832479Y298230D03*
X840354Y308070D03*
X836419Y315945D03*
X832479Y308070D03*
X856104Y298230D03*
X852164Y290355D03*
X848229Y298230D03*
X844289Y290355D03*
X856104Y308070D03*
X852164Y315945D03*
X844289D03*
X871849Y298230D03*
X867914Y290355D03*
X863974Y298230D03*
X871849Y308070D03*
X867914Y315945D03*
X863974Y308070D03*
G54D39*
X1066929Y43267D03*
X1057086D03*
X1074803D03*
X1272441Y7087D03*
X1299213D03*
G54D41*
X1224016Y180709D03*
G54D24*
X200000Y401500D03*
Y411500D03*
Y421500D03*
X216500Y401500D03*
Y411500D03*
Y421500D03*
X945197Y380000D03*
X968819D03*
X1296000Y319500D03*
Y329500D03*
X1367067Y42323D03*
Y78544D03*
X1392657Y42323D03*
Y78544D03*
G54D28*
X402953Y23622D03*
X413189D03*
X423425D03*
G54D33*
X590315Y9134D03*
Y19134D03*
X649527Y9134D03*
Y19134D03*
Y29134D03*
G54D15*
X35435Y373228D03*
X82675D03*
G54D44*
X1272677Y349016D03*
G54D29*
X404920Y330117D03*
X412794D03*
X412815Y349860D03*
X408857Y341928D03*
Y365550D03*
Y357676D03*
Y385237D03*
Y377363D03*
Y400985D03*
Y393111D03*
Y416733D03*
Y408859D03*
Y424607D03*
X420668Y330117D03*
X424605Y345865D03*
Y369487D03*
Y361613D03*
Y353739D03*
Y385237D03*
X428542Y400985D03*
X424605D03*
Y393111D03*
X428542Y397048D03*
X420668Y400985D03*
X428523Y416683D03*
X416731Y416733D03*
Y404922D03*
X423555Y431500D03*
X416731Y420670D03*
Y424607D03*
X430513Y320841D03*
X440353Y349802D03*
X444290D03*
X440353Y341928D03*
X436416Y345865D03*
X440353Y369487D03*
X444290Y365550D03*
X440353Y353739D03*
X444290Y357676D03*
X432479Y369487D03*
Y361613D03*
X444290Y385237D03*
Y377363D03*
X440353Y381300D03*
X432479Y385237D03*
X436416Y377363D03*
X432479D03*
X440353Y400985D03*
Y389174D03*
X432479Y400985D03*
Y397048D03*
Y393111D03*
Y389174D03*
X444323Y416883D03*
X436523Y416683D03*
X442535Y426770D03*
X434723Y426283D03*
X456103Y330117D03*
X460040Y349802D03*
Y341928D03*
X448227Y349802D03*
X456103Y365550D03*
Y357676D03*
X460040Y369487D03*
Y361613D03*
X448227Y369487D03*
Y361613D03*
Y353739D03*
X456103Y385237D03*
Y377363D03*
X460040Y381300D03*
X448227D03*
X460040Y389174D03*
X448227D03*
X456103Y400985D03*
X460040D03*
X456103Y393111D03*
X460040D03*
Y397048D03*
X448227Y400985D03*
Y393111D03*
X456103Y412796D03*
X460023Y408883D03*
X450725Y425460D03*
X471851Y322243D03*
Y326180D03*
X463977Y330117D03*
X475788Y349802D03*
Y341928D03*
X467914Y349802D03*
X475788Y369487D03*
Y361613D03*
Y357676D03*
X467914Y369487D03*
Y361613D03*
Y365550D03*
Y357676D03*
Y353739D03*
X463977Y365550D03*
Y357676D03*
Y385237D03*
X475788Y381300D03*
Y377363D03*
X467914Y385237D03*
Y377363D03*
Y381300D03*
X463977Y377363D03*
X475788Y400985D03*
Y397048D03*
Y393111D03*
X471851D03*
Y397048D03*
X475788Y389174D03*
X467914Y400985D03*
Y397048D03*
Y393111D03*
Y389174D03*
X463977Y393111D03*
Y397048D03*
X471851Y412796D03*
X475788Y424607D03*
X493855Y312700D03*
X488155Y315700D03*
X490455Y319200D03*
X481255Y320000D03*
X491536Y334054D03*
X479725Y330117D03*
X479655Y322500D03*
X491536Y341928D03*
X479725Y337991D03*
Y369487D03*
Y361613D03*
X487643Y361523D03*
X491500Y353500D03*
X491536Y385237D03*
Y377363D03*
X479725Y381300D03*
X491536Y400985D03*
Y393111D03*
X479725Y397048D03*
Y389174D03*
X491536Y416733D03*
Y408859D03*
X487599Y416733D03*
X483662Y408859D03*
X487599Y404922D03*
X479725Y412796D03*
X491536Y420670D03*
Y424607D03*
X483662D03*
X487599D03*
X505678Y310921D03*
X506000Y317500D03*
X498855Y311100D03*
X498955Y316900D03*
X505523Y332086D03*
X499410Y322243D03*
X511500Y348000D03*
X511455Y338700D03*
X505523Y363582D03*
X507955Y356100D03*
X505523Y371456D03*
X503347Y381300D03*
Y397048D03*
Y389174D03*
X499410Y416733D03*
Y412796D03*
Y408859D03*
X503347D03*
Y404922D03*
X495473Y416733D03*
Y412796D03*
Y408859D03*
X499410Y420670D03*
Y424607D03*
X503347Y420670D03*
X495473Y424607D03*
Y420670D03*
X1020500Y882500D03*
Y887000D03*
X1011966Y893534D03*
X1020282Y911218D03*
X1034000Y155000D03*
X1021468Y866968D03*
X1032600Y867657D03*
X1031500Y884500D03*
X1035216Y884468D03*
X1035000Y888500D03*
Y880500D03*
Y970000D03*
X1039468Y155284D03*
X1048968D03*
X1053500Y153000D03*
X1044000D03*
X1048968Y150784D03*
X1039500Y151000D03*
X1048968Y159284D03*
X1039500Y159500D03*
X1053500Y157500D03*
X1044000D03*
X1045968Y185500D03*
X1039000Y884500D03*
X1051000Y883600D03*
Y888500D03*
X1065000Y154000D03*
X1057968Y155284D03*
X1058000Y150500D03*
Y159500D03*
X1060509Y177126D03*
X1058000Y889500D03*
Y902500D03*
Y896000D03*
X1055000Y970000D03*
X1084988Y154203D03*
X1080500Y153500D03*
X1077500Y150000D03*
X1085150Y158400D03*
X1075000Y970000D03*
X1105000D03*
X1125000D03*
X1145000D03*
X1175000D03*
X1195000D03*
X1215000D03*
X1259968Y444284D03*
X1260000Y448500D03*
X1264500Y446500D03*
X1260000Y440000D03*
X1264500Y442000D03*
X1257468Y478500D03*
X1278500Y448500D03*
Y444000D03*
X1274000Y447000D03*
X1269468Y444284D03*
Y448284D03*
X1278500Y439500D03*
X1269468Y439784D03*
X1274000Y442000D03*
X1270000Y477000D03*
X1288000Y442000D03*
X1292500Y441000D03*
X1318000Y369500D03*
Y375500D03*
Y381500D03*
X1330000Y428000D03*
X1331500Y432500D03*
X1344000Y434500D03*
X1340200D03*
Y438300D03*
X1343900Y438500D03*
X1343000Y466500D03*
G54D10*
X8590Y318590D03*
X4500Y329297D03*
Y349297D03*
Y369297D03*
Y389297D03*
Y409297D03*
Y429297D03*
Y449297D03*
Y469297D03*
Y489297D03*
Y509297D03*
Y529297D03*
Y549297D03*
Y569297D03*
Y589297D03*
Y609297D03*
Y629297D03*
Y649297D03*
Y669297D03*
Y689297D03*
Y709297D03*
Y729297D03*
Y749297D03*
Y769297D03*
Y789297D03*
Y809297D03*
Y829297D03*
Y849297D03*
X8442Y847311D03*
X4500Y869297D03*
Y889297D03*
Y909297D03*
Y929297D03*
Y949297D03*
Y969297D03*
X20000Y380000D03*
Y440000D03*
Y460000D03*
Y480000D03*
Y500000D03*
X50395Y384679D03*
X40945Y384710D03*
X48820Y412435D03*
X39370Y412673D03*
X40054Y823970D03*
X36004Y839500D03*
X38804Y906220D03*
X41500Y941500D03*
X46500Y944500D03*
X59840Y384679D03*
X67715Y412518D03*
X58270Y412485D03*
X60304Y663220D03*
X64304Y698720D03*
X63304Y706720D03*
X64272Y736004D03*
X55304Y849720D03*
X78740Y384915D03*
X69290Y384865D03*
X77165Y412590D03*
X76804Y662720D03*
X73804Y699720D03*
X81304Y710220D03*
X76272Y762504D03*
X77804Y773720D03*
X71804Y789720D03*
X73772Y822004D03*
X69804Y835720D03*
X83838Y848133D03*
X76804Y847720D03*
X81804Y888720D03*
X72770Y906488D03*
X95304Y663720D03*
X97737Y698653D03*
X96060Y762476D03*
X100804Y774720D03*
X99804Y799720D03*
X85804Y816220D03*
X87804Y835720D03*
X98304Y888220D03*
X97804Y940720D03*
X112654Y314453D03*
X111304Y663720D03*
X111907Y698617D03*
X115804Y798720D03*
X101804Y940720D03*
X112900Y988500D03*
X132500Y312500D03*
X124500Y316000D03*
X122874Y354709D03*
X132804Y894220D03*
X134874Y354709D03*
X147374D03*
X149100Y661100D03*
X143010Y676400D03*
X162595Y296709D03*
X153437Y320458D03*
X155874Y310209D03*
X152995Y329119D03*
X159674Y328609D03*
X159774Y320709D03*
X158874Y354709D03*
X163225Y522080D03*
X154755Y539310D03*
X166875Y678285D03*
X153500Y690275D03*
X163000Y901000D03*
X158000D03*
X172285Y296964D03*
X181889Y297303D03*
X183374Y328709D03*
X171874D03*
X171295Y320709D03*
X180315Y321209D03*
X170374Y354709D03*
X170339Y537396D03*
X180555Y560500D03*
X175055Y569500D03*
X172040Y688960D03*
X181000Y901000D03*
X174500Y901500D03*
X168500Y901000D03*
X197245Y296571D03*
X196063Y319209D03*
X192874Y326209D03*
Y337907D03*
X189000Y347600D03*
X192500Y431500D03*
X190800Y462800D03*
X189355Y526470D03*
X195725Y540750D03*
X198000Y785000D03*
X191875Y803125D03*
X188000Y901000D03*
X197000D03*
Y897000D03*
X207086Y297418D03*
X205511Y320709D03*
X214960Y321044D03*
X212500Y435000D03*
X208305Y562640D03*
X201000Y625500D03*
X212500Y786000D03*
X204500Y817500D03*
X205500Y901000D03*
Y897000D03*
X217295Y296709D03*
X232500Y419000D03*
Y431000D03*
X231500Y898500D03*
X242500Y565500D03*
X240000Y829250D03*
X236500Y866000D03*
X261500Y188900D03*
X256300Y188800D03*
X258800Y184200D03*
X261400Y179800D03*
X255800Y179600D03*
X258500Y608500D03*
Y613500D03*
X253500Y608500D03*
X253555Y613500D03*
X261500Y857500D03*
X262178Y976000D03*
X261178Y981040D03*
X268300Y219800D03*
X273000Y674000D03*
X269000Y921500D03*
X274000D03*
X273678Y958000D03*
X268178Y955500D03*
X297929Y332000D03*
Y336000D03*
X293929Y342000D03*
X285678Y995500D03*
X293178D03*
X299500Y5500D03*
X299300Y84200D03*
X311500Y153000D03*
X299000Y148000D03*
X307129Y143000D03*
X305029Y147700D03*
X304300Y160200D03*
X304100Y167000D03*
X311300D03*
X312500Y159100D03*
X305429Y219400D03*
Y223000D03*
X311500Y272000D03*
X307500Y299000D03*
X303545Y445840D03*
X300112Y483783D03*
X305155Y504900D03*
X305255Y542600D03*
X301178Y995500D03*
X309678D03*
X321000Y29000D03*
Y33500D03*
Y38000D03*
Y57000D03*
Y52500D03*
Y48000D03*
Y42500D03*
Y61500D03*
X316900Y65900D03*
X320500Y66000D03*
X330250Y80000D03*
X317660Y96400D03*
X330900Y134500D03*
X329929Y128500D03*
X325929Y127700D03*
X319014Y152977D03*
X328700Y154400D03*
X328629Y146800D03*
X330400Y141600D03*
X318200Y159100D03*
X329929Y241500D03*
X316000Y271500D03*
X326000Y292500D03*
X327000Y308000D03*
X331000Y308018D03*
X322429Y349300D03*
X320238Y497183D03*
X316273Y520282D03*
X321555Y534500D03*
X315135Y554980D03*
X324678Y995500D03*
X317178D03*
X336700Y4300D03*
X341200D03*
X346000Y4400D03*
X338000Y127500D03*
X337400Y134500D03*
X334000Y147600D03*
X345929Y183000D03*
X340679Y204900D03*
X332429Y210000D03*
X346404Y260000D03*
X344429Y312000D03*
X341500Y309500D03*
X345929Y336500D03*
X341351Y336434D03*
X335645Y445630D03*
X343095Y446200D03*
X338595Y482590D03*
X339140Y512500D03*
X336445Y509330D03*
X343555Y517000D03*
X340715Y545840D03*
X339500Y936500D03*
X333500Y954000D03*
X341178Y996000D03*
X332678Y995500D03*
X355000Y4400D03*
X350500D03*
X360400D03*
X362500Y64000D03*
X352500Y113000D03*
X357394Y131496D03*
X348429Y130000D03*
X353929Y128500D03*
X351429Y126500D03*
X362009Y142520D03*
Y148819D03*
Y155119D03*
X362036Y170876D03*
X362034Y161406D03*
X353085Y187485D03*
X355040Y180000D03*
X362017Y183492D03*
X354540Y199000D03*
X353300Y218400D03*
X352429Y279000D03*
X357929Y277000D03*
X348000Y292500D03*
X357055Y385000D03*
Y380500D03*
Y376500D03*
X355055Y394000D03*
Y389500D03*
X364055Y512000D03*
X351815Y546880D03*
X364000Y869500D03*
X358268Y995500D03*
X348678Y996000D03*
X364900Y4400D03*
X369400D03*
X370000Y51000D03*
Y55500D03*
Y60000D03*
X368307Y133071D03*
X374606Y136221D03*
X371458Y142520D03*
X377765Y155146D03*
X374589Y155110D03*
X371455Y148854D03*
X377787Y148812D03*
X365186Y170876D03*
X377732Y167703D03*
X377718Y161417D03*
X371470Y167741D03*
X371489Y161411D03*
X365186Y177175D03*
X368320Y183460D03*
X377741Y177188D03*
X377731Y180302D03*
X371457Y173978D03*
X368336Y189755D03*
X368307Y196062D03*
Y202361D03*
X377755D03*
Y199211D03*
Y196062D03*
Y192912D03*
Y189763D03*
X374607Y218110D03*
X374606Y211810D03*
X366000Y277500D03*
X372055Y319500D03*
X369555Y322500D03*
X371555Y347500D03*
X375805Y380250D03*
X371781Y387924D03*
X373555Y482500D03*
X367555Y545500D03*
X380000Y872000D03*
X371938Y922438D03*
X377953Y995725D03*
X390354Y136221D03*
X380906Y136220D03*
X384055Y155117D03*
X396653D03*
X380907Y142520D03*
X387206Y145670D03*
X390355Y142520D03*
X393505Y145670D03*
X384093Y151968D03*
X393519Y151990D03*
X384055Y158266D03*
X396653D03*
X390354Y167715D03*
X396653D03*
X384032Y167703D03*
X380944Y161417D03*
X387219Y158290D03*
X390392Y186614D03*
X384055Y186613D03*
X396654Y186614D03*
X396653Y174015D03*
Y180314D03*
X387204Y177164D03*
X384032Y174003D03*
X384055Y202361D03*
X393503Y205510D03*
X396654Y202362D03*
X396653Y205511D03*
Y199211D03*
X384055Y192912D03*
Y196062D03*
X396653Y192912D03*
X393503Y211809D03*
X380906Y211810D03*
X396654D03*
X396653Y208660D03*
X393503D03*
X390354Y218109D03*
Y221259D03*
Y224408D03*
X391000Y238500D03*
X394929Y247000D03*
X386755Y447300D03*
X396055Y456500D03*
X389000Y604000D03*
X395500Y867000D03*
X396500Y910500D03*
X383500Y938500D03*
X389763Y996085D03*
X402950Y133050D03*
X399835Y139375D03*
X412429Y136210D03*
X412415Y148794D03*
X399779Y142531D03*
X399804Y145670D03*
X412403Y142520D03*
X406102Y155117D03*
X412402Y155118D03*
X412401Y151967D03*
X399819Y151950D03*
X406125Y148804D03*
X402952Y167715D03*
X409251D03*
X412401Y158267D03*
X406102D03*
X402977Y174003D03*
X402952Y186613D03*
X409251D03*
X409288Y180315D03*
X402952Y180314D03*
X409251Y174015D03*
X412401Y205510D03*
X402952Y192912D03*
X409251D03*
X402953Y211810D03*
X412402D03*
X399803Y218109D03*
Y221259D03*
Y208660D03*
X409929Y245400D03*
X412513Y294800D03*
X398385Y292540D03*
X401555Y318000D03*
X410500Y885500D03*
X401500Y994500D03*
X415549Y151990D03*
X418702Y142520D03*
X425001D03*
X428149Y164565D03*
Y170865D03*
X421876Y167705D03*
X415575Y167703D03*
X424999Y161416D03*
X428149Y183463D03*
Y177164D03*
X421876Y174005D03*
Y180304D03*
Y186603D03*
X415551Y186614D03*
X415587Y180315D03*
X415551Y174015D03*
X424999Y199211D03*
X428149D03*
X424999Y202361D03*
X428149D03*
X421876Y192902D03*
X428149Y192912D03*
X415551D03*
X418701Y211810D03*
X425001D03*
X420429Y246400D03*
X416500Y284800D03*
X422500Y271501D03*
X428542Y330117D03*
X425178Y798000D03*
X418278Y828000D03*
Y840000D03*
X418500Y857500D03*
X418278Y854000D03*
Y846500D03*
X419500Y914000D03*
X425000Y994500D03*
X430540Y108750D03*
X434449Y155118D03*
X431300Y142520D03*
X437599D03*
X431299Y164565D03*
Y170865D03*
X434449Y167716D03*
Y161417D03*
X431299Y161416D03*
Y183463D03*
X434449Y180314D03*
Y174015D03*
X431299Y177164D03*
X434448Y186613D03*
X431299D03*
X434414Y205514D03*
X434449Y199212D03*
Y192913D03*
Y211810D03*
X436500Y241000D03*
X439000Y254500D03*
X440500Y267000D03*
X444255Y283700D03*
X430900Y294550D03*
X436416Y330117D03*
X444290D03*
X436416Y357676D03*
X432178Y798000D03*
X438178Y798500D03*
X444678Y798400D03*
X442278Y846000D03*
X431500Y886000D03*
X437678D03*
X443178D03*
X435678Y996000D03*
X443178D03*
X457500Y121000D03*
X457429Y171500D03*
X458429Y185000D03*
X459500Y290100D03*
X448227Y341928D03*
X458685Y425710D03*
X456178Y798000D03*
X452978Y805400D03*
X455278Y846000D03*
X451278D03*
X459278D03*
X451178Y886000D03*
X460678D03*
X457578Y879700D03*
X458678Y996000D03*
X450178D03*
X471429Y133500D03*
X465679Y192600D03*
X469155Y297800D03*
X474755Y308300D03*
X466655Y425340D03*
X472055Y425000D03*
X475678Y798500D03*
X463178D03*
X469178D03*
X467278Y846000D03*
X468178Y886000D03*
X472178D03*
X474178Y995500D03*
X466178Y996000D03*
X481929Y126500D03*
X490100Y162100D03*
X492555Y431250D03*
X482178Y886000D03*
X489678Y995500D03*
X482178D03*
X503929Y127500D03*
X499629Y178400D03*
X498855Y302851D03*
X495555Y369500D03*
X507355Y390800D03*
X497778Y843000D03*
Y838500D03*
Y847000D03*
X498500Y867500D03*
X505678Y995500D03*
X498178D03*
X525679Y136250D03*
X517679Y125750D03*
X513407Y311502D03*
X513500Y315800D03*
X522345Y311699D03*
X522365Y316365D03*
X521800Y322000D03*
X527667Y322182D03*
X523500Y347500D03*
Y352000D03*
Y342000D03*
X523100Y364300D03*
X526800Y359600D03*
X519500Y365500D03*
X523500Y357500D03*
X521500Y632500D03*
X521178Y995500D03*
X513678D03*
X538875Y138000D03*
X542000Y249000D03*
X528600Y316700D03*
X539300Y317600D03*
X534000Y317500D03*
X539200Y324100D03*
X530000Y342000D03*
X529400Y352800D03*
X530100Y347200D03*
X536678Y996000D03*
X530083Y995500D03*
X546500Y147500D03*
X547500Y360168D03*
X560678Y996000D03*
X577000Y58000D03*
X568500Y147500D03*
X574000Y269000D03*
X563250Y262500D03*
X571555Y326000D03*
X562055Y347500D03*
X567500Y457500D03*
X563000Y453000D03*
X567500D03*
Y462000D03*
Y466500D03*
X563000Y457500D03*
Y462000D03*
Y466500D03*
X569178Y996000D03*
X576678D03*
X579221Y237250D03*
X580828Y260028D03*
X584678Y994500D03*
X604500Y205000D03*
Y200500D03*
X603500Y218500D03*
Y214000D03*
X594500Y236000D03*
X610500Y333000D03*
X606000Y341500D03*
X609000Y345500D03*
X598178Y983500D03*
X615000Y333000D03*
X620500D03*
X611500Y341500D03*
X613500Y345500D03*
X616500Y341500D03*
X621500D03*
X642000Y335000D03*
X639000Y332000D03*
X638500Y409000D03*
X634500Y427000D03*
X637000Y431500D03*
X632500D03*
X637000Y436500D03*
X632500D03*
X641625Y465375D03*
X628250Y570200D03*
X646500Y101000D03*
X650500D03*
X651500Y408500D03*
X646500D03*
X647125Y429375D03*
X656162Y472338D03*
X654500Y494000D03*
X647252Y576500D03*
X662248Y101000D03*
X670454Y94544D03*
X667748Y104000D03*
X670522Y130200D03*
X673500Y334000D03*
X668000D03*
X662000D03*
X663500Y452000D03*
X672500D03*
X660000Y443500D03*
X663500Y456000D03*
Y460500D03*
X667500Y454000D03*
Y458500D03*
X672500Y456000D03*
Y460500D03*
X690966Y142028D03*
X687055Y258500D03*
X683055D03*
X678055D03*
X681000Y452000D03*
X690500Y468000D03*
X681000Y456000D03*
Y460500D03*
X676500Y454000D03*
Y458500D03*
X690000Y460500D03*
X687968Y755284D03*
Y781784D03*
X700000Y60500D03*
X703053Y133568D03*
X704716Y156520D03*
X700216Y156368D03*
X706055Y258500D03*
X705500Y352500D03*
X707000Y340500D03*
X708500Y365000D03*
X707000Y385000D03*
Y378000D03*
X708500Y371000D03*
X694000Y483500D03*
X693500Y472000D03*
X694000Y492000D03*
Y500500D03*
Y507500D03*
Y514000D03*
X705900Y569200D03*
X698818Y759350D03*
X703328Y800144D03*
X697250Y876750D03*
X715716Y82652D03*
X713716Y121284D03*
X721716Y112784D03*
Y116784D03*
X717716Y121284D03*
X721716D03*
Y129284D03*
Y125284D03*
X722716Y156520D03*
X718216D03*
X713716D03*
X709216D03*
X721200Y205800D03*
X710055Y258500D03*
X714055D03*
X711500Y385000D03*
Y378000D03*
X720500Y478750D03*
X723168Y774984D03*
X712500Y859750D03*
X716250Y860250D03*
X723000Y996500D03*
X729716Y121284D03*
X725716D03*
X727248Y141500D03*
X727216Y156520D03*
X733498Y180750D03*
X733000Y193000D03*
X732500Y485500D03*
X734500Y547500D03*
X734462Y553538D03*
X733268Y757984D03*
X735000Y780500D03*
X727468Y819284D03*
X733440Y875560D03*
X731498Y996500D03*
X739368Y996610D03*
X727558Y996500D03*
X757200Y103100D03*
X746716Y130238D03*
X750916Y130272D03*
X745500Y145000D03*
X756000Y180000D03*
X749750Y454000D03*
X755300Y489300D03*
X746750Y571750D03*
X748000Y579500D03*
X745400Y877600D03*
X761000Y88500D03*
Y82500D03*
X760600Y94500D03*
X760522Y116784D03*
X770000Y123500D03*
X770500Y136000D03*
X770900Y144300D03*
X765116Y187659D03*
X771000Y464000D03*
X765009Y563491D03*
X760125Y666875D03*
X770646Y685354D03*
X777500Y351000D03*
X782500D03*
X788600Y449300D03*
X784800D03*
X776468Y447600D03*
X784900Y453000D03*
X788800D03*
X784274Y486274D03*
X790600Y547600D03*
X790000Y554500D03*
X785500Y666500D03*
X783746Y692754D03*
X787500Y783500D03*
X782750Y845750D03*
X781000Y877000D03*
X776750Y964750D03*
X806274Y434726D03*
X791000Y562000D03*
X802500Y579500D03*
X794000Y723500D03*
X791500Y783500D03*
X805250Y865750D03*
X794500Y897000D03*
X800500Y977500D03*
X794500D03*
X800500Y982000D03*
X794500D03*
X818500Y361600D03*
X813500Y367000D03*
X811000Y430500D03*
X810000Y735500D03*
X814000Y849500D03*
X810000Y980000D03*
X838055Y262500D03*
X828500Y361500D03*
X837000D03*
X825500Y411100D03*
X832500Y404000D03*
X826500Y436000D03*
X826000Y465078D03*
X831000Y598500D03*
X839250Y854500D03*
X826060Y863440D03*
X840000Y980000D03*
X847055Y262500D03*
X851555D03*
X854820Y352380D03*
X846500Y362000D03*
X842000Y367000D03*
Y372000D03*
Y377500D03*
X852000Y401500D03*
X842000D03*
X847000Y396500D03*
Y401500D03*
Y406500D03*
X854000Y436500D03*
X846250Y642250D03*
X854000Y640500D03*
X852500Y710500D03*
X842500Y719500D03*
X852600Y868500D03*
X872000Y75500D03*
X866112Y85626D03*
X865055Y262500D03*
X871500Y484000D03*
X871000Y639500D03*
X870500Y665060D03*
X861250Y649250D03*
X865500Y690500D03*
X860500Y734000D03*
X870000Y980000D03*
X888750Y324660D03*
X884120Y351630D03*
X877000Y409500D03*
X874450Y463500D03*
X877500Y612500D03*
X884200Y636500D03*
X878500Y695500D03*
X902000Y63000D03*
X904600Y406600D03*
X900000Y980000D03*
X935000Y51500D03*
X937000Y63000D03*
X936000Y373500D03*
X934000Y448700D03*
X968085Y452065D03*
X980078Y204578D03*
X980960Y195257D03*
X989000Y66500D03*
X996500Y167000D03*
X988660Y190500D03*
X998000Y461500D03*
X1002500Y520000D03*
X994500Y543800D03*
X1001000Y771500D03*
X1007000Y12000D03*
X1012000Y43000D03*
X1017274Y219274D03*
X1013000Y282500D03*
X1012900Y275300D03*
X1007500Y487500D03*
X1016500Y519500D03*
X1008500Y543700D03*
X1007032Y879968D03*
X1010000Y980000D03*
X1032000Y82500D03*
Y90000D03*
Y97000D03*
Y103500D03*
Y110000D03*
X1036019Y203177D03*
X1036000Y199500D03*
X1035922Y209578D03*
X1031800Y248800D03*
X1027500Y248500D03*
X1036300Y248800D03*
X1042500Y930000D03*
X1040000Y980000D03*
X1066500Y185500D03*
X1060000Y207500D03*
X1060500Y282500D03*
X1060600Y303150D03*
X1056100Y303200D03*
X1059900Y295200D03*
X1059800Y290600D03*
X1061696Y761294D03*
X1061356Y753354D03*
X1071000Y71000D03*
X1077250Y102000D03*
X1077500Y97000D03*
Y107500D03*
X1086000Y126500D03*
X1074500Y185500D03*
X1072500Y208924D03*
X1074500Y627500D03*
X1073000Y637500D03*
X1071500Y739000D03*
X1077500Y759000D03*
X1085468Y895968D03*
X1070000Y980000D03*
X1088000Y85500D03*
X1098000Y126500D03*
X1102000Y250000D03*
X1102500Y264500D03*
X1089500Y405000D03*
X1088400Y647484D03*
X1098000Y775000D03*
X1093000Y791000D03*
X1097500Y784500D03*
X1098500Y823344D03*
X1092718Y859984D03*
X1093468Y896968D03*
X1100000Y980000D03*
X1113500Y614250D03*
X1113000Y630500D03*
X1105000D03*
X1110790Y738850D03*
X1107000Y757500D03*
X1114500Y855500D03*
X1119000D03*
X1118034Y847034D03*
X1113768D03*
X1116468Y870284D03*
Y874284D03*
Y865784D03*
X1112468Y870284D03*
X1114500Y886000D03*
X1103000Y888300D03*
X1118500Y886000D03*
X1123000Y250500D03*
X1120600Y282300D03*
X1126000Y618000D03*
X1122985Y670262D03*
X1122938Y676540D03*
X1119265Y683864D03*
X1135551Y685967D03*
X1135570Y711218D03*
X1132398Y720624D03*
X1132960Y752950D03*
X1126210Y752810D03*
X1134245Y769145D03*
X1127945Y769970D03*
X1121215Y769936D03*
X1135000Y810000D03*
X1134244Y799984D03*
X1121000Y808500D03*
X1127945Y799935D03*
X1121646Y799924D03*
X1121000Y823500D03*
X1123500Y832470D03*
X1135500Y835000D03*
X1135468Y854032D03*
X1120468Y870284D03*
X1131275Y867725D03*
X1130000Y980000D03*
X1145800Y282284D03*
X1151500Y449000D03*
X1147000Y619000D03*
X1151337Y660807D03*
X1141868Y680064D03*
X1151337Y670256D03*
X1151300Y682854D03*
Y692303D03*
Y689153D03*
Y686004D03*
Y695452D03*
X1148150D03*
Y692303D03*
Y689153D03*
Y686004D03*
Y682854D03*
X1151300Y698602D03*
X1148150D03*
X1145265Y776945D03*
X1151592Y773748D03*
X1140650Y782496D03*
X1151565Y787951D03*
X1142110Y792660D03*
X1149400Y800000D03*
X1142010Y809500D03*
X1137000Y890000D03*
X1144500D03*
X1152000D03*
X1166000Y232000D03*
X1162468Y257968D03*
X1168000Y302500D03*
X1166000Y290000D03*
X1168076Y310046D03*
X1152500Y311000D03*
X1158000Y309500D03*
X1152500Y318500D03*
X1160000D03*
X1167000Y321000D03*
Y326450D03*
X1155000Y594500D03*
X1165476Y613393D03*
X1152500Y608500D03*
X1165672Y609672D03*
X1159100Y640800D03*
X1154218Y679964D03*
X1154496Y667096D03*
X1160748Y682854D03*
X1157599Y686004D03*
X1154449D03*
Y682854D03*
Y689153D03*
X1160748Y695452D03*
X1157599D03*
Y692303D03*
X1154449Y695452D03*
Y692303D03*
X1163898Y695452D03*
X1160748Y692303D03*
X1163898D03*
X1157599Y689153D03*
X1160748D03*
X1163898D03*
X1160748Y686004D03*
X1163898D03*
Y698602D03*
X1160748D03*
X1157599D03*
X1154449D03*
X1166100Y731500D03*
X1152023Y733299D03*
X1160333Y753600D03*
X1167320Y770290D03*
X1157871Y773728D03*
X1167330Y795830D03*
X1163605Y783513D03*
X1167277Y792658D03*
X1157866Y795844D03*
X1165300Y809610D03*
X1160300D03*
X1154300D03*
X1155390Y818000D03*
X1157990Y827000D03*
X1158000Y890000D03*
X1164500D03*
X1155000Y980000D03*
X1171000Y232000D03*
X1177500Y290000D03*
X1174752Y320504D03*
X1175000Y327000D03*
X1176500Y383500D03*
X1182500Y407000D03*
X1179934Y567000D03*
X1176496Y698564D03*
X1179671Y698565D03*
X1184750Y781000D03*
X1170300Y809610D03*
X1186500Y232000D03*
X1196334Y290561D03*
X1185283Y290513D03*
X1198000Y348000D03*
X1192000Y344500D03*
X1197000Y372500D03*
X1187500Y411000D03*
X1197000Y409500D03*
X1185945Y695415D03*
X1196000Y710500D03*
X1188000Y762500D03*
X1198718Y800782D03*
X1188875Y856625D03*
X1185000Y980000D03*
X1208500Y202000D03*
X1209000Y212500D03*
X1208000Y231000D03*
X1201922Y248500D03*
X1202177Y260000D03*
X1208500Y283500D03*
X1208000Y271499D03*
Y297638D03*
Y309000D03*
X1206500Y330000D03*
X1208500Y321500D03*
X1203500Y345000D03*
X1208500Y346400D03*
Y359000D03*
X1208000Y371000D03*
X1209000Y438500D03*
X1209500Y561910D03*
X1215500Y605300D03*
X1203500Y698520D03*
X1210500Y733500D03*
X1201968Y757500D03*
X1212840Y781000D03*
X1204000Y862000D03*
X1217250Y862250D03*
X1211500Y882500D03*
X1215000Y980000D03*
X1225500Y714500D03*
X1230500Y841000D03*
X1239500Y204000D03*
Y214000D03*
X1239000Y251500D03*
X1241777Y265700D03*
X1241377Y274900D03*
X1238500Y290000D03*
X1239000Y302437D03*
X1238500Y316500D03*
X1250158Y326463D03*
X1238500Y325985D03*
X1239000Y338900D03*
Y352800D03*
X1239500Y366000D03*
X1234177Y379500D03*
X1243000Y446650D03*
X1249000Y723250D03*
X1248500Y775500D03*
X1248950Y782450D03*
X1245650Y821850D03*
X1245000Y980000D03*
X1256500Y166500D03*
X1261000D03*
X1265000Y169000D03*
Y174000D03*
X1258000Y205000D03*
X1265000Y211500D03*
X1261000Y207500D03*
Y211500D03*
X1251500Y266500D03*
X1251700Y274000D03*
X1254203Y282770D03*
X1261000Y292500D03*
X1261006Y303543D03*
X1252564Y290566D03*
X1253500Y316500D03*
Y305000D03*
X1257000Y311000D03*
X1258562Y672438D03*
X1259000Y699500D03*
X1257500Y710500D03*
X1259500Y724000D03*
X1264000Y853000D03*
X1281000Y475000D03*
X1276500D03*
X1271000Y573500D03*
Y568500D03*
X1282500Y598000D03*
Y645000D03*
X1282300Y678000D03*
X1276000Y694000D03*
X1272700Y694900D03*
X1277000Y712500D03*
X1272500D03*
X1275000Y732000D03*
X1277500Y757500D03*
Y778500D03*
X1267500Y779000D03*
X1275000Y980000D03*
X1290874Y34376D03*
X1295500Y291500D03*
X1285500Y475000D03*
X1293500D03*
X1297500Y562000D03*
X1286500Y569000D03*
X1291500Y666000D03*
X1298034Y907034D03*
X1309500Y51000D03*
X1311000Y435000D03*
X1307900Y577412D03*
X1306617Y587512D03*
X1308817Y595412D03*
X1311000Y651900D03*
X1306000Y782500D03*
X1314284D03*
X1304500Y838000D03*
X1300784Y838716D03*
X1303750Y862250D03*
X1307468Y884532D03*
X1300000Y980000D03*
X1331000Y120000D03*
X1322000Y318500D03*
X1319400Y522100D03*
X1318700Y533500D03*
X1323117Y626412D03*
X1329468Y666468D03*
X1318784Y793716D03*
X1321466Y907034D03*
X1330000Y980000D03*
X1347000Y88000D03*
X1347500Y116000D03*
X1334500Y557000D03*
X1344617Y588712D03*
Y593412D03*
X1346617Y626912D03*
X1342367Y627662D03*
X1333468Y680000D03*
X1354500Y276000D03*
X1358500Y288916D03*
X1354900Y522600D03*
X1355900Y536600D03*
X1355500Y556500D03*
X1360817Y557812D03*
X1349317Y593412D03*
X1353117Y610412D03*
X1363100Y627000D03*
X1349817Y628612D03*
X1360000Y980000D03*
X1369720Y106365D03*
X1375500Y328000D03*
X1378500Y370000D03*
Y365000D03*
Y360000D03*
X1377000Y384000D03*
Y379000D03*
X1378500Y374500D03*
X1377000Y390000D03*
X1374500Y395000D03*
Y402000D03*
X1372500Y415000D03*
X1368000Y450500D03*
X1369617Y557012D03*
X1378800Y594900D03*
X1390004Y106000D03*
G54D45*
X1338526Y29526D03*
G54D32*
X545079Y315945D03*
X556889Y298230D03*
X552954Y290355D03*
X560829Y315945D03*
X572639Y298230D03*
X568699Y290355D03*
X576574Y315945D03*
X564764Y308070D03*
X588384Y298230D03*
X584449Y290355D03*
X592324Y315945D03*
X580514Y308070D03*
X604134Y298230D03*
X600199Y290355D03*
X608069Y315945D03*
X596259Y308070D03*
X619884Y298230D03*
X615944Y290355D03*
X627754Y308070D03*
X623819Y315945D03*
X612009Y308070D03*
X635629Y298230D03*
X631694Y290355D03*
X643504Y308070D03*
X639569Y315945D03*
X651379Y298230D03*
X647439Y290355D03*
X659254Y308070D03*
X655314Y315945D03*
X667124Y298230D03*
X663189Y290355D03*
X674999Y308070D03*
X671064Y315945D03*
X682874Y298230D03*
X678939Y290355D03*
X690749Y308070D03*
X686809Y315945D03*
X698624Y298230D03*
X694684Y290355D03*
X706494Y308070D03*
X702559Y315945D03*
X726179Y290355D03*
X714369Y298230D03*
X710434Y290355D03*
X722244Y308070D03*
X718309Y315945D03*
X741929Y290355D03*
X730119Y298230D03*
X737994Y308070D03*
X734054Y315945D03*
X757679Y290355D03*
X745864Y298230D03*
X753739Y308070D03*
X749804Y315945D03*
X773424Y290355D03*
X761614Y298230D03*
X769489Y308070D03*
X765549Y315945D03*
X789174Y290355D03*
X777364Y298230D03*
X785234Y308070D03*
X781299Y315945D03*
X804919Y290355D03*
X793109Y298230D03*
X800984Y308070D03*
X797049Y315945D03*
X820669Y290355D03*
X808859Y298230D03*
X816734Y308070D03*
X812794Y315945D03*
X848229Y308070D03*
X860039Y290355D03*
Y315945D03*
G54D23*
X200000Y391500D03*
X216500D03*
G54D46*
X1367067Y60039D03*
Y96260D03*
X1392657Y60039D03*
Y96260D03*
G54D30*
X537994Y303150D03*
X825984D03*
G54D37*
X1008268Y244094D03*
Y411417D03*
X1227166Y155511D03*
X1227165Y411417D03*
G54D14*
X15000Y1008622D03*
X90119Y72219D03*
X227041Y1008622D03*
X653974Y1008621D03*
X955315Y850829D03*
X1157095Y128841D03*
X1385000Y1008622D03*
X1387875Y-15015D03*
G54D26*
X270078Y92125D03*
Y155117D03*
X490944Y79921D03*
Y255118D03*
X743897Y353543D03*
Y410629D03*
X1305117Y87548D03*
Y262745D03*
X1376968Y147243D03*
Y216535D03*
G54D38*
X1045000Y32598D03*
X1096732D03*
G54D35*
X600925Y44134D03*
X638917D03*
G54D27*
X332086Y408858D03*
X355708Y96456D03*
X450196Y257874D03*
X572243Y337992D03*
G54D16*
X25000Y980000D03*
X45000D03*
X55000Y975000D03*
X65000Y980000D03*
X75000Y975000D03*
X95000D03*
X206000Y982000D03*
X226000D03*
X246000D03*
X324500Y6000D03*
Y10500D03*
X1105000Y15000D03*
Y75000D03*
Y105000D03*
Y135000D03*
X1211500Y5500D03*
Y35500D03*
Y65500D03*
Y85500D03*
Y107500D03*
Y137500D03*
G54D20*
X140000Y720000D03*
Y740000D03*
X158500Y461500D03*
X182800Y465800D03*
X180000Y760000D03*
X220000D03*
X260000Y260000D03*
Y760000D03*
X378500Y812000D03*
Y824500D03*
X406500Y713500D03*
X412000Y724000D03*
X409500Y775500D03*
X422500Y764500D03*
X440000Y5000D03*
X431000Y713500D03*
Y724000D03*
X460000Y5000D03*
X477500Y715000D03*
X485000Y5000D03*
X491500Y715000D03*
X490500Y800000D03*
X504500Y715000D03*
X502500Y800000D03*
X515000Y5000D03*
X545000D03*
X560000Y20000D03*
X575000Y5000D03*
X604500Y714500D03*
X606000Y918500D03*
X616500Y714500D03*
X613500Y744500D03*
Y759000D03*
X620500Y848500D03*
X634000Y734500D03*
X633500Y749500D03*
X630500Y912000D03*
X650000Y110000D03*
X657500Y827000D03*
X656500Y906000D03*
X660000Y120000D03*
X685000Y5000D03*
X682500Y917500D03*
X695000Y20000D03*
X715000Y5000D03*
X725000Y20000D03*
X720000Y905000D03*
X728966Y53966D03*
Y65466D03*
X745000Y5000D03*
X755000Y20000D03*
X747800Y50200D03*
X762250Y71000D03*
X775000Y5000D03*
X785000Y20000D03*
X805000Y5000D03*
X800000Y100000D03*
X815000Y20000D03*
X810000Y120000D03*
X820500Y754000D03*
Y765500D03*
X835000Y5000D03*
X850000Y20000D03*
X865000Y5000D03*
X870000Y160000D03*
X880000Y20000D03*
X895000Y5000D03*
X890000Y140000D03*
X910000Y20000D03*
Y160000D03*
X915000Y805000D03*
Y825000D03*
Y845000D03*
Y865000D03*
Y885000D03*
Y905000D03*
Y925000D03*
Y945000D03*
Y965000D03*
X925000Y5000D03*
X955000D03*
X940000Y20000D03*
X970000D03*
X965000Y725500D03*
X985000Y5000D03*
X980000Y725500D03*
X1000000Y20000D03*
X1000500Y667500D03*
X990000D03*
X1015000Y5000D03*
X1045000D03*
X1060000Y20000D03*
X1075000Y5000D03*
X1090000Y20000D03*
X1100000Y180000D03*
X1091500Y846500D03*
X1105000Y5000D03*
Y400500D03*
X1235500Y5000D03*
X1268000D03*
X1307500D03*
X1305217Y612412D03*
X1305435Y603918D03*
X1337500Y5000D03*
X1354500Y703500D03*
X1379600Y584200D03*
X1377800Y603800D03*
X1378082Y614266D03*
X1381637Y611225D03*
X1381578Y607117D03*
X1394122Y5878D03*
X1387200Y584100D03*
X1384400Y598300D03*
Y601900D03*
G54D21*
X153937Y238898D03*
Y246772D03*
Y260551D03*
X224015Y234961D03*
Y246772D03*
Y260551D03*
G54D34*
X585315Y44134D03*
X654527D03*
G54D25*
X200118Y739409D03*
X190118D03*
X210118D03*
X230118Y729409D03*
Y739409D03*
X220118D03*
X250118D03*
X240118D03*
X260118Y729409D03*
Y739409D03*
X270118Y729409D03*
Y739409D03*
G54D11*
X19272Y337795D03*
Y396850D03*
X98838Y337795D03*
Y396850D03*
G54D40*
X1084646Y43267D03*
%LPC*%
G75*
G54D48*
G01X-245081Y-422119D02*
G02I-12000J0D01*
G01X-250231D02*
G02I-6850J0D01*
G01X-241081D02*
X-273081D01*
G01X-257081Y-438119D02*
Y-406119D01*
G01X-241081Y-438119D02*
Y-518119D01*
G01D02*
X1034819D01*
G01X-241081Y-473619D02*
X1034819D01*
G01X-241081Y-438119D02*
X1034819D01*
G01X247319D02*
Y-518119D01*
G01X384819Y-438119D02*
Y-518119D01*
G01X499819Y-438119D02*
Y-518119D01*
G01X667319Y-438119D02*
Y-518119D01*
G01X837319Y-438119D02*
Y-518119D01*
G01X1034819Y-438119D02*
Y-518119D01*
G01X1066819Y-422119D02*
X1034819D01*
G01X1050819Y-438119D02*
Y-406119D01*
G01X1062819Y-422119D02*
G02I-12000J0D01*
G01X1057669D02*
G02I-6850J0D01*
G54D49*
G01X-185516Y-508119D02*
Y-490619D01*
G01X-176346D02*
Y-508119D01*
G01Y-499369D02*
X-185516D01*
G01X-163431Y-508119D02*
X-165178Y-507827D01*
X-166706Y-506661D01*
X-168016Y-504911D01*
X-168890Y-502869D01*
X-169326Y-500536D01*
Y-498202D01*
X-168890Y-495869D01*
X-168016Y-493827D01*
X-166706Y-492078D01*
X-165178Y-490911D01*
X-163431Y-490619D01*
X-161685Y-490911D01*
X-160156Y-492078D01*
X-158846Y-493827D01*
X-157972Y-495869D01*
X-157536Y-498202D01*
Y-500536D01*
X-157972Y-502869D01*
X-158846Y-504911D01*
X-160156Y-506661D01*
X-161685Y-507827D01*
X-163431Y-508119D01*
G01X-150953D02*
Y-490619D01*
X-140909Y-508119D01*
Y-490619D01*
G01X-124064Y-508119D02*
X-132798D01*
Y-490619D01*
X-124064D01*
G01X-127558Y-499077D02*
X-132798D01*
G01X-110931Y-508119D02*
Y-500244D01*
X-115298Y-490619D01*
G01X-106564D02*
X-110931Y-500244D01*
G01X-74185Y-498786D02*
X-73311Y-497911D01*
X-72656Y-496453D01*
X-72219Y-494410D01*
X-72656Y-492661D01*
X-73529Y-491494D01*
X-75058Y-490619D01*
X-80953D01*
Y-508119D01*
X-73748D01*
X-72219Y-506953D01*
X-71346Y-505202D01*
X-70909Y-503161D01*
X-71346Y-501119D01*
X-72656Y-499369D01*
X-74185Y-498786D01*
X-80953D01*
G01X-63890Y-508119D02*
X-58431Y-490619D01*
X-52972Y-508119D01*
G01X-54938Y-501994D02*
X-61925D01*
G01X-45734Y-508119D02*
Y-490619D01*
X-41368D01*
X-39621Y-491494D01*
X-38311Y-492661D01*
X-37219Y-494410D01*
X-36346Y-496453D01*
X-36128Y-499369D01*
X-36346Y-502286D01*
X-37219Y-504328D01*
X-38311Y-506078D01*
X-39621Y-507244D01*
X-41368Y-508119D01*
X-45734D01*
G01X-22121Y-499369D02*
X-17754D01*
Y-504619D01*
X-19064Y-506369D01*
X-20593Y-507536D01*
X-22776Y-508119D01*
X-24959Y-507536D01*
X-26488Y-506369D01*
X-27798Y-504619D01*
X-28671Y-502577D01*
X-29108Y-500244D01*
Y-498202D01*
X-28671Y-496453D01*
X-27798Y-494410D01*
X-26488Y-492661D01*
X-25178Y-491494D01*
X-23431Y-490619D01*
X-21903D01*
X-20156Y-491202D01*
X-18846Y-492369D01*
G01X-1564Y-508119D02*
X-10298D01*
Y-490619D01*
X-1564D01*
G01X-5058Y-499077D02*
X-10298D01*
G01X7202Y-508119D02*
Y-490619D01*
X12661D01*
X14407Y-491494D01*
X15499Y-492661D01*
X15936Y-494994D01*
X15499Y-497328D01*
X14189Y-498786D01*
X12661Y-499661D01*
X7202D01*
G01X12661D02*
X15936Y-508119D01*
G01X48315Y-498786D02*
X49189Y-497911D01*
X49844Y-496453D01*
X50281Y-494410D01*
X49844Y-492661D01*
X48971Y-491494D01*
X47442Y-490619D01*
X41547D01*
Y-508119D01*
X48752D01*
X50281Y-506953D01*
X51154Y-505202D01*
X51591Y-503161D01*
X51154Y-501119D01*
X49844Y-499369D01*
X48315Y-498786D01*
X41547D01*
G01X58610Y-508119D02*
X64069Y-490619D01*
X69528Y-508119D01*
G01X67562Y-501994D02*
X60575D01*
G01X76984Y-505786D02*
X78731Y-507244D01*
X80696Y-508119D01*
X82442D01*
X84189Y-507244D01*
X85499Y-505786D01*
X86154Y-503744D01*
X85717Y-501703D01*
X84626Y-499952D01*
X82661Y-498786D01*
X80041Y-498202D01*
X78512Y-497036D01*
X77857Y-494994D01*
X78294Y-492952D01*
X79386Y-491494D01*
X80914Y-490619D01*
X82442D01*
X83971Y-491202D01*
X85281Y-492661D01*
G01X103436Y-508119D02*
X94702D01*
Y-490619D01*
X103436D01*
G01X99942Y-499077D02*
X94702D01*
G01X118315Y-498786D02*
X119189Y-497911D01*
X119844Y-496453D01*
X120281Y-494410D01*
X119844Y-492661D01*
X118971Y-491494D01*
X117442Y-490619D01*
X111547D01*
Y-508119D01*
X118752D01*
X120281Y-506953D01*
X121154Y-505202D01*
X121591Y-503161D01*
X121154Y-501119D01*
X119844Y-499369D01*
X118315Y-498786D01*
X111547D01*
G01X134069Y-508119D02*
X132322Y-507827D01*
X130794Y-506661D01*
X129484Y-504911D01*
X128610Y-502869D01*
X128174Y-500536D01*
Y-498202D01*
X128610Y-495869D01*
X129484Y-493827D01*
X130794Y-492078D01*
X132322Y-490911D01*
X134069Y-490619D01*
X135815Y-490911D01*
X137344Y-492078D01*
X138654Y-493827D01*
X139528Y-495869D01*
X139964Y-498202D01*
Y-500536D01*
X139528Y-502869D01*
X138654Y-504911D01*
X137344Y-506661D01*
X135815Y-507827D01*
X134069Y-508119D01*
G01X146110D02*
X151569Y-490619D01*
X157028Y-508119D01*
G01X155062Y-501994D02*
X148075D01*
G01X164702Y-508119D02*
Y-490619D01*
X170161D01*
X171907Y-491494D01*
X172999Y-492661D01*
X173436Y-494994D01*
X172999Y-497328D01*
X171689Y-498786D01*
X170161Y-499661D01*
X164702D01*
G01X170161D02*
X173436Y-508119D01*
G01X181766D02*
Y-490619D01*
X186132D01*
X187879Y-491494D01*
X189189Y-492661D01*
X190281Y-494410D01*
X191154Y-496453D01*
X191372Y-499369D01*
X191154Y-502286D01*
X190281Y-504328D01*
X189189Y-506078D01*
X187879Y-507244D01*
X186132Y-508119D01*
X181766D01*
G01X-37858Y-463119D02*
Y-445619D01*
X-32181Y-460202D01*
X-26504Y-445619D01*
Y-463119D01*
G01X-14681D02*
X-15991Y-462827D01*
X-17301Y-461661D01*
X-18175Y-459619D01*
X-18611Y-457286D01*
X-18175Y-454952D01*
X-17301Y-452911D01*
X-15991Y-451744D01*
X-14681Y-451453D01*
X-13371Y-451744D01*
X-12061Y-452911D01*
X-11188Y-454952D01*
X-10969Y-457286D01*
X-11188Y-459619D01*
X-12061Y-461661D01*
X-13371Y-462827D01*
X-14681Y-463119D01*
G01X6749Y-445619D02*
Y-463119D01*
G01Y-460495D02*
X5876Y-461953D01*
X4565Y-462827D01*
X3037Y-463119D01*
X1291Y-462536D01*
X-19Y-461078D01*
X-893Y-459328D01*
X-1111Y-457286D01*
X-893Y-455244D01*
X-19Y-453494D01*
X1291Y-452036D01*
X3037Y-451453D01*
X4565Y-451744D01*
X5657Y-452328D01*
X6749Y-453494D01*
G01X17044Y-455244D02*
X24031D01*
X23376Y-453202D01*
X22284Y-452036D01*
X20756Y-451453D01*
X19227Y-451744D01*
X17917Y-452619D01*
X17044Y-454661D01*
X16607Y-456411D01*
Y-458161D01*
X17044Y-459911D01*
X18136Y-461661D01*
X19446Y-462827D01*
X20974Y-463119D01*
X22502Y-462536D01*
X24031Y-460786D01*
G01X37819Y-463119D02*
Y-445619D01*
G01X281019Y-508119D02*
Y-490619D01*
X278399Y-494119D01*
G01Y-508119D02*
X283639D01*
G01X293716Y-504619D02*
X295025Y-506661D01*
X296772Y-507827D01*
X298737Y-508119D01*
X300484Y-507827D01*
X302231Y-506369D01*
X303322Y-504619D01*
X303541Y-502869D01*
X303104Y-500828D01*
X301576Y-499369D01*
X300047Y-498786D01*
X298082D01*
G01X300047D02*
X301357Y-497911D01*
X302449Y-496453D01*
X302886Y-494703D01*
X302449Y-492952D01*
X301357Y-491494D01*
X299392Y-490619D01*
X297427Y-490911D01*
X295462Y-492078D01*
G01X312307Y-506078D02*
X313836Y-507536D01*
X315582Y-508119D01*
X317329Y-507536D01*
X318857Y-505786D01*
X319949Y-503161D01*
X320386Y-500536D01*
Y-497328D01*
X319949Y-494703D01*
X318857Y-492369D01*
X317547Y-491202D01*
X316019Y-490619D01*
X314272Y-491202D01*
X312962Y-492369D01*
X312089Y-494119D01*
X311652Y-496453D01*
X312089Y-498494D01*
X313181Y-500536D01*
X314491Y-501703D01*
X316019Y-501994D01*
X317765Y-501411D01*
X319076Y-499952D01*
X320386Y-497328D01*
G01X336139Y-508119D02*
Y-490619D01*
X328060Y-503161D01*
X338978D01*
G01X351019Y-508119D02*
X352547Y-507827D01*
X354294Y-506953D01*
X355386Y-505495D01*
X355822Y-503452D01*
X355386Y-501411D01*
X354076Y-499661D01*
X352111Y-498786D01*
X349927D01*
X348617Y-498202D01*
X347525Y-496744D01*
X347089Y-494703D01*
X347744Y-492661D01*
X349272Y-491202D01*
X351019Y-490619D01*
X352765Y-491202D01*
X354294Y-492661D01*
X354949Y-494703D01*
X354512Y-496744D01*
X353421Y-498202D01*
X352111Y-498786D01*
X349927D01*
X347962Y-499661D01*
X346652Y-501411D01*
X346216Y-503452D01*
X346652Y-505495D01*
X347744Y-506953D01*
X349491Y-507827D01*
X351019Y-508119D01*
G01X267902Y-463119D02*
Y-445619D01*
X273142D01*
X274889Y-446494D01*
X276199Y-448536D01*
X276636Y-450869D01*
X276199Y-453202D01*
X275107Y-454952D01*
X273142Y-455828D01*
X267902D01*
G01X294572Y-447078D02*
X293262Y-446202D01*
X291734Y-445619D01*
X289987D01*
X288022Y-446494D01*
X286494Y-447952D01*
X285402Y-449703D01*
X284529Y-452619D01*
X284310Y-455244D01*
X284747Y-457869D01*
X285402Y-459619D01*
X286712Y-461369D01*
X288241Y-462536D01*
X289769Y-463119D01*
X291297D01*
X292826Y-462536D01*
X294136Y-461661D01*
X295228Y-460495D01*
G01X309015Y-453786D02*
X309889Y-452911D01*
X310544Y-451453D01*
X310981Y-449410D01*
X310544Y-447661D01*
X309671Y-446494D01*
X308142Y-445619D01*
X302247D01*
Y-463119D01*
X309452D01*
X310981Y-461953D01*
X311854Y-460202D01*
X312291Y-458161D01*
X311854Y-456119D01*
X310544Y-454369D01*
X309015Y-453786D01*
X302247D01*
G01X318219Y-468952D02*
X331319D01*
G01X337247Y-463119D02*
Y-445619D01*
X347291Y-463119D01*
Y-445619D01*
G01X359769Y-463119D02*
X358022Y-462827D01*
X356494Y-461661D01*
X355184Y-459911D01*
X354310Y-457869D01*
X353874Y-455536D01*
Y-453202D01*
X354310Y-450869D01*
X355184Y-448827D01*
X356494Y-447078D01*
X358022Y-445911D01*
X359769Y-445619D01*
X361515Y-445911D01*
X363044Y-447078D01*
X364354Y-448827D01*
X365228Y-450869D01*
X365664Y-453202D01*
Y-455536D01*
X365228Y-457869D01*
X364354Y-459911D01*
X363044Y-461661D01*
X361515Y-462827D01*
X359769Y-463119D01*
G01X410610Y-445619D02*
X416069Y-463119D01*
X421528Y-445619D01*
G01X437936Y-463119D02*
X429202D01*
Y-445619D01*
X437936D01*
G01X434442Y-454077D02*
X429202D01*
G01X446702Y-463119D02*
Y-445619D01*
X452161D01*
X453907Y-446494D01*
X454999Y-447661D01*
X455436Y-449994D01*
X454999Y-452328D01*
X453689Y-453786D01*
X452161Y-454661D01*
X446702D01*
G01X452161D02*
X455436Y-463119D01*
G01X468569Y-463702D02*
X468132Y-463411D01*
Y-462827D01*
X468569Y-462536D01*
X469006Y-462827D01*
Y-463411D01*
X468569Y-463702D01*
G01X433569Y-508119D02*
Y-490619D01*
X430949Y-494119D01*
G01Y-508119D02*
X436189D01*
G01X452815Y-498786D02*
X453689Y-497911D01*
X454344Y-496453D01*
X454781Y-494410D01*
X454344Y-492661D01*
X453471Y-491494D01*
X451942Y-490619D01*
X446047D01*
Y-508119D01*
X453252D01*
X454781Y-506953D01*
X455654Y-505202D01*
X456091Y-503161D01*
X455654Y-501119D01*
X454344Y-499369D01*
X452815Y-498786D01*
X446047D01*
G01X544152Y-490619D02*
Y-508119D01*
X552886D01*
G01X561871Y-493536D02*
X563181Y-491786D01*
X564709Y-490911D01*
X566456Y-490619D01*
X568639Y-491202D01*
X570167Y-492661D01*
X570604Y-494410D01*
X570386Y-496161D01*
X569512Y-497619D01*
X565146Y-500536D01*
X563181Y-502577D01*
X561871Y-505495D01*
X561434Y-508119D01*
X570604D01*
G01X584829Y-499369D02*
X589196D01*
Y-504619D01*
X587886Y-506369D01*
X586357Y-507536D01*
X584174Y-508119D01*
X581991Y-507536D01*
X580462Y-506369D01*
X579152Y-504619D01*
X578279Y-502577D01*
X577842Y-500244D01*
Y-498202D01*
X578279Y-496453D01*
X579152Y-494410D01*
X580462Y-492661D01*
X581772Y-491494D01*
X583519Y-490619D01*
X585047D01*
X586794Y-491202D01*
X588104Y-492369D01*
G01X595997Y-508119D02*
Y-490619D01*
X606041Y-508119D01*
Y-490619D01*
G01X613716Y-508119D02*
Y-490619D01*
X618082D01*
X619829Y-491494D01*
X621139Y-492661D01*
X622231Y-494410D01*
X623104Y-496453D01*
X623322Y-499369D01*
X623104Y-502286D01*
X622231Y-504328D01*
X621139Y-506078D01*
X619829Y-507244D01*
X618082Y-508119D01*
X613716D01*
G01X544152Y-445619D02*
Y-463119D01*
X552886D01*
G01X569949D02*
Y-451453D01*
G01Y-453494D02*
X569076Y-452328D01*
X567765Y-451744D01*
X566237Y-451453D01*
X564709Y-452036D01*
X563399Y-453202D01*
X562525Y-454952D01*
X562089Y-457286D01*
X562525Y-459619D01*
X563399Y-461369D01*
X564709Y-462536D01*
X566237Y-463119D01*
X567765Y-462827D01*
X569076Y-461953D01*
X569949Y-460786D01*
G01X578934Y-468369D02*
X580244Y-468952D01*
X581991Y-468369D01*
X583082Y-467203D01*
X583956Y-465744D01*
X585265Y-461078D01*
X588104Y-451453D01*
G01X581117D02*
X585265Y-461078D01*
G01X597744Y-455244D02*
X604731D01*
X604076Y-453202D01*
X602984Y-452036D01*
X601456Y-451453D01*
X599927Y-451744D01*
X598617Y-452619D01*
X597744Y-454661D01*
X597307Y-456411D01*
Y-458161D01*
X597744Y-459911D01*
X598836Y-461661D01*
X600146Y-462827D01*
X601674Y-463119D01*
X603202Y-462536D01*
X604731Y-460786D01*
G01X615462Y-463119D02*
Y-451453D01*
G01Y-453786D02*
X616554Y-452619D01*
X617646Y-451744D01*
X619174Y-451453D01*
X620265Y-451744D01*
X621576Y-452619D01*
G01X686702Y-490619D02*
Y-508119D01*
X695436D01*
G01X703984Y-513369D02*
X705294Y-513952D01*
X707041Y-513369D01*
X708132Y-512203D01*
X709006Y-510744D01*
X710315Y-506078D01*
X713154Y-496453D01*
G01X706167D02*
X710315Y-506078D01*
G01X722357Y-508119D02*
Y-496453D01*
G01Y-499369D02*
X723231Y-497911D01*
X724541Y-496744D01*
X726287Y-496453D01*
X727815Y-496744D01*
X729126Y-497911D01*
X729781Y-499952D01*
Y-508119D01*
G01X739857D02*
Y-496453D01*
G01Y-499369D02*
X740731Y-497911D01*
X742041Y-496744D01*
X743787Y-496453D01*
X745315Y-496744D01*
X746626Y-497911D01*
X747281Y-499952D01*
Y-508119D01*
G01X774202Y-490619D02*
Y-508119D01*
X782936D01*
G01X796069Y-496453D02*
Y-508119D01*
G01Y-491786D02*
X795632Y-491494D01*
Y-490911D01*
X796069Y-490619D01*
X796506Y-490911D01*
Y-491494D01*
X796069Y-491786D01*
G01X809857Y-496453D02*
Y-504619D01*
X810731Y-506661D01*
X812041Y-507827D01*
X813569Y-508119D01*
X815097Y-507827D01*
X816407Y-506661D01*
X817281Y-504619D01*
G01Y-508119D02*
Y-496453D01*
G01X686266Y-463119D02*
Y-445619D01*
X690632D01*
X692379Y-446494D01*
X693689Y-447661D01*
X694781Y-449410D01*
X695654Y-451453D01*
X695872Y-454369D01*
X695654Y-457286D01*
X694781Y-459328D01*
X693689Y-461078D01*
X692379Y-462244D01*
X690632Y-463119D01*
X686266D01*
G01X705294Y-455244D02*
X712281D01*
X711626Y-453202D01*
X710534Y-452036D01*
X709006Y-451453D01*
X707477Y-451744D01*
X706167Y-452619D01*
X705294Y-454661D01*
X704857Y-456411D01*
Y-458161D01*
X705294Y-459911D01*
X706386Y-461661D01*
X707696Y-462827D01*
X709224Y-463119D01*
X710752Y-462536D01*
X712281Y-460786D01*
G01X722794Y-461078D02*
X723886Y-462244D01*
X725414Y-463119D01*
X726724D01*
X728034Y-462536D01*
X728907Y-461661D01*
X729344Y-460495D01*
X729126Y-458744D01*
X728252Y-457869D01*
X724322Y-456119D01*
X723449Y-454077D01*
X723886Y-452619D01*
X724759Y-451744D01*
X726069Y-451453D01*
X727379Y-451744D01*
X728689Y-452619D01*
G01X743569Y-451453D02*
Y-463119D01*
G01Y-446786D02*
X743132Y-446494D01*
Y-445911D01*
X743569Y-445619D01*
X744006Y-445911D01*
Y-446494D01*
X743569Y-446786D01*
G01X758012Y-467494D02*
X759541Y-468661D01*
X761287Y-468952D01*
X762815Y-468661D01*
X764126Y-467203D01*
X764999Y-465161D01*
Y-451453D01*
G01Y-453786D02*
X764126Y-452619D01*
X762815Y-451744D01*
X761287Y-451453D01*
X759541Y-452036D01*
X758449Y-453202D01*
X757575Y-455244D01*
X757139Y-457286D01*
X757357Y-459036D01*
X758231Y-461078D01*
X759541Y-462536D01*
X761287Y-463119D01*
X762597Y-462827D01*
X764126Y-461661D01*
X764999Y-460495D01*
G01X774857Y-463119D02*
Y-451453D01*
G01Y-454369D02*
X775731Y-452911D01*
X777041Y-451744D01*
X778787Y-451453D01*
X780315Y-451744D01*
X781626Y-452911D01*
X782281Y-454952D01*
Y-463119D01*
G01X792794Y-455244D02*
X799781D01*
X799126Y-453202D01*
X798034Y-452036D01*
X796506Y-451453D01*
X794977Y-451744D01*
X793667Y-452619D01*
X792794Y-454661D01*
X792357Y-456411D01*
Y-458161D01*
X792794Y-459911D01*
X793886Y-461661D01*
X795196Y-462827D01*
X796724Y-463119D01*
X798252Y-462536D01*
X799781Y-460786D01*
G01X810512Y-463119D02*
Y-451453D01*
G01Y-453786D02*
X811604Y-452619D01*
X812696Y-451744D01*
X814224Y-451453D01*
X815315Y-451744D01*
X816626Y-452619D01*
G01X857269Y-508119D02*
Y-490619D01*
X854649Y-494119D01*
G01Y-508119D02*
X859889D01*
G01X874769D02*
Y-490619D01*
X872149Y-494119D01*
G01Y-508119D02*
X877389D01*
G01X888339Y-508702D02*
X896199Y-490619D01*
G01X909769Y-508119D02*
Y-490619D01*
X907149Y-494119D01*
G01Y-508119D02*
X912389D01*
G01X922466Y-504619D02*
X923775Y-506661D01*
X925522Y-507827D01*
X927487Y-508119D01*
X929234Y-507827D01*
X930981Y-506369D01*
X932072Y-504619D01*
X932291Y-502869D01*
X931854Y-500828D01*
X930326Y-499369D01*
X928797Y-498786D01*
X926832D01*
G01X928797D02*
X930107Y-497911D01*
X931199Y-496453D01*
X931636Y-494703D01*
X931199Y-492952D01*
X930107Y-491494D01*
X928142Y-490619D01*
X926177Y-490911D01*
X924212Y-492078D01*
G01X940839Y-508702D02*
X948699Y-490619D01*
G01X958121Y-493536D02*
X959431Y-491786D01*
X960959Y-490911D01*
X962706Y-490619D01*
X964889Y-491202D01*
X966417Y-492661D01*
X966854Y-494410D01*
X966636Y-496161D01*
X965762Y-497619D01*
X961396Y-500536D01*
X959431Y-502577D01*
X958121Y-505495D01*
X957684Y-508119D01*
X966854D01*
G01X979769Y-490619D02*
X978022Y-491202D01*
X976712Y-492661D01*
X975839Y-494410D01*
X975184Y-496744D01*
X974966Y-499369D01*
X975184Y-501994D01*
X975839Y-504328D01*
X976712Y-506078D01*
X978022Y-507536D01*
X979769Y-508119D01*
X981515Y-507536D01*
X982826Y-506078D01*
X983699Y-504328D01*
X984354Y-501994D01*
X984572Y-499369D01*
X984354Y-496744D01*
X983699Y-494410D01*
X982826Y-492661D01*
X981515Y-491202D01*
X979769Y-490619D01*
G01X997269Y-508119D02*
Y-490619D01*
X994649Y-494119D01*
G01Y-508119D02*
X999889D01*
G01X1017389D02*
Y-490619D01*
X1009310Y-503161D01*
X1020228D01*
G01X904966Y-463119D02*
Y-445619D01*
X909332D01*
X911079Y-446494D01*
X912389Y-447661D01*
X913481Y-449410D01*
X914354Y-451453D01*
X914572Y-454369D01*
X914354Y-457286D01*
X913481Y-459328D01*
X912389Y-461078D01*
X911079Y-462244D01*
X909332Y-463119D01*
X904966D01*
G01X931199D02*
Y-451453D01*
G01Y-453494D02*
X930326Y-452328D01*
X929015Y-451744D01*
X927487Y-451453D01*
X925959Y-452036D01*
X924649Y-453202D01*
X923775Y-454952D01*
X923339Y-457286D01*
X923775Y-459619D01*
X924649Y-461369D01*
X925959Y-462536D01*
X927487Y-463119D01*
X929015Y-462827D01*
X930326Y-461953D01*
X931199Y-460786D01*
G01X944769Y-445619D02*
Y-463119D01*
G01X941712Y-451453D02*
X947826D01*
G01X958994Y-455244D02*
X965981D01*
X965326Y-453202D01*
X964234Y-452036D01*
X962706Y-451453D01*
X961177Y-451744D01*
X959867Y-452619D01*
X958994Y-454661D01*
X958557Y-456411D01*
Y-458161D01*
X958994Y-459911D01*
X960086Y-461661D01*
X961396Y-462827D01*
X962924Y-463119D01*
X964452Y-462536D01*
X965981Y-460786D01*
M02*
